(kicad_sch
	(version 20250114)
	(generator "eeschema")
	(generator_version "9.0")
	(paper "A3")
	(title_block
		(title "SO-DIMM DDR5 Tester")
		(date "2025-11-26")
		(rev "1.3.0")
		(company "Antmicro Ltd.")
		(comment 1 "www.antmicro.com")
		(comment 2 "Antmicro Ltd")
	)
	(text "VCCADC max: 2.0V"
		(exclude_from_sim no)
		(at 219.075 93.98 0)
		(effects
			(font
				(size 1.27 1.27)
			)
			(justify left bottom)
		)
	)
	(text "BANK 32\n"
		(exclude_from_sim no)
		(at 116.84 152.4 0)
		(effects
			(font
				(size 1.27 1.27)
			)
			(justify left bottom)
		)
	)
	(text "FPGA Power rails"
		(exclude_from_sim no)
		(at 13.335 18.415 0)
		(effects
			(font
				(size 2.4892 2.4892)
				(thickness 0.4978)
				(bold yes)
			)
			(justify left bottom)
		)
	)
	(text "BANK 14"
		(exclude_from_sim no)
		(at 40.64 211.455 0)
		(effects
			(font
				(size 1.27 1.27)
			)
			(justify left bottom)
		)
	)
	(text "V_{CCAUX}"
		(exclude_from_sim no)
		(at 90.805 111.76 0)
		(effects
			(font
				(size 1.27 1.27)
			)
			(justify left bottom)
		)
	)
	(text "BANK 34"
		(exclude_from_sim no)
		(at 116.205 212.09 0)
		(effects
			(font
				(size 1.27 1.27)
			)
			(justify left bottom)
		)
	)
	(text "BANK 0"
		(exclude_from_sim no)
		(at 40.64 151.765 0)
		(effects
			(font
				(size 1.27 1.27)
			)
			(justify left bottom)
		)
	)
	(text "VCCBATT max: 2.0V"
		(exclude_from_sim no)
		(at 219.075 101.6 0)
		(effects
			(font
				(size 1.27 1.27)
			)
			(justify left bottom)
		)
	)
	(text "BANK 12"
		(exclude_from_sim no)
		(at 40.64 180.34 0)
		(effects
			(font
				(size 1.27 1.27)
			)
			(justify left bottom)
		)
	)
	(text "Trace length from the resistor pins to the\nFPGA pins MGTRREF and MGTAVTTRCAL\nmust be equal in length."
		(exclude_from_sim no)
		(at 293.37 107.95 0)
		(effects
			(font
				(size 1 1)
			)
			(justify left bottom)
		)
	)
	(text "BANK 33"
		(exclude_from_sim no)
		(at 117.475 180.975 0)
		(effects
			(font
				(size 1.27 1.27)
			)
			(justify left bottom)
		)
	)
	(text "VCCINT max: 1.1V"
		(exclude_from_sim no)
		(at 219.075 81.28 0)
		(effects
			(font
				(size 1.27 1.27)
			)
			(justify left bottom)
		)
	)
	(text "BANK 16"
		(exclude_from_sim no)
		(at 40.005 237.49 0)
		(effects
			(font
				(size 1.27 1.27)
			)
			(justify left bottom)
		)
	)
	(text "V_{CCINT}"
		(exclude_from_sim no)
		(at 55.245 57.785 0)
		(effects
			(font
				(size 1.27 1.27)
			)
			(justify left bottom)
		)
	)
	(text "VCCAUX max: 2.0V"
		(exclude_from_sim no)
		(at 219.075 86.36 0)
		(effects
			(font
				(size 1.27 1.27)
			)
			(justify left bottom)
		)
	)
	(text "Bank marked by dahed line \nreferenced from 7 Series FPGAs\nPCB Design Guide UG483 \n(FFG+FBG Package worst case)"
		(exclude_from_sim no)
		(at 13.97 27.305 0)
		(effects
			(font
				(size 1.27 1.27)
			)
			(justify left bottom)
		)
	)
	(text "V_{CCBRAM}"
		(exclude_from_sim no)
		(at 127 57.785 0)
		(effects
			(font
				(size 1.27 1.27)
			)
			(justify left bottom)
		)
	)
	(text "VCCBRAM max: 1.1V"
		(exclude_from_sim no)
		(at 219.075 106.68 0)
		(effects
			(font
				(size 1.27 1.27)
			)
			(justify left bottom)
		)
	)
	(text "MGT decoupling marked by dahed line \nreferenced from 7 Series FPGAs\nPCB Design Guide UG482 \n(FFG+FBG Package worst case)"
		(exclude_from_sim no)
		(at 13.97 36.195 0)
		(effects
			(font
				(size 1.27 1.27)
			)
			(justify left bottom)
		)
	)
	(junction
		(at 356.235 55.245)
		(diameter 0)
		(color 0 0 0 0)
	)
	(junction
		(at 347.98 55.245)
		(diameter 0)
		(color 0 0 0 0)
	)
	(junction
		(at 293.37 95.25)
		(diameter 0)
		(color 0 0 0 0)
	)
	(junction
		(at 59.69 181.61)
		(diameter 0)
		(color 0 0 0 0)
	)
	(junction
		(at 133.35 113.665)
		(diameter 0)
		(color 0 0 0 0)
	)
	(junction
		(at 311.15 92.71)
		(diameter 0)
		(color 0 0 0 0)
	)
	(junction
		(at 136.525 212.725)
		(diameter 0)
		(color 0 0 0 0)
	)
	(junction
		(at 331.47 55.245)
		(diameter 0)
		(color 0 0 0 0)
	)
	(junction
		(at 66.675 181.61)
		(diameter 0)
		(color 0 0 0 0)
	)
	(junction
		(at 344.805 118.745)
		(diameter 0)
		(color 0 0 0 0)
	)
	(junction
		(at 238.76 113.03)
		(diameter 0)
		(color 0 0 0 0)
	)
	(junction
		(at 47.625 84.455)
		(diameter 0)
		(color 0 0 0 0)
	)
	(junction
		(at 59.69 212.725)
		(diameter 0)
		(color 0 0 0 0)
	)
	(junction
		(at 52.705 181.61)
		(diameter 0)
		(color 0 0 0 0)
	)
	(junction
		(at 163.83 84.455)
		(diameter 0)
		(color 0 0 0 0)
	)
	(junction
		(at 45.72 181.61)
		(diameter 0)
		(color 0 0 0 0)
	)
	(junction
		(at 39.37 84.455)
		(diameter 0)
		(color 0 0 0 0)
	)
	(junction
		(at 45.72 153.035)
		(diameter 0)
		(color 0 0 0 0)
	)
	(junction
		(at 208.28 87.63)
		(diameter 0)
		(color 0 0 0 0)
	)
	(junction
		(at 151.13 181.61)
		(diameter 0)
		(color 0 0 0 0)
	)
	(junction
		(at 139.065 84.455)
		(diameter 0)
		(color 0 0 0 0)
	)
	(junction
		(at 238.76 87.63)
		(diameter 0)
		(color 0 0 0 0)
	)
	(junction
		(at 92.075 113.665)
		(diameter 0)
		(color 0 0 0 0)
	)
	(junction
		(at 52.705 212.725)
		(diameter 0)
		(color 0 0 0 0)
	)
	(junction
		(at 38.1 238.76)
		(diameter 0)
		(color 0 0 0 0)
	)
	(junction
		(at 52.07 238.76)
		(diameter 0)
		(color 0 0 0 0)
	)
	(junction
		(at 45.085 238.76)
		(diameter 0)
		(color 0 0 0 0)
	)
	(junction
		(at 122.555 84.455)
		(diameter 0)
		(color 0 0 0 0)
	)
	(junction
		(at 46.99 113.665)
		(diameter 0)
		(color 0 0 0 0)
	)
	(junction
		(at 80.645 181.61)
		(diameter 0)
		(color 0 0 0 0)
	)
	(junction
		(at 64.135 113.665)
		(diameter 0)
		(color 0 0 0 0)
	)
	(junction
		(at 108.585 113.665)
		(diameter 0)
		(color 0 0 0 0)
	)
	(junction
		(at 73.66 113.665)
		(diameter 0)
		(color 0 0 0 0)
	)
	(junction
		(at 73.66 212.725)
		(diameter 0)
		(color 0 0 0 0)
	)
	(junction
		(at 39.37 60.325)
		(diameter 0)
		(color 0 0 0 0)
	)
	(junction
		(at 114.3 84.455)
		(diameter 0)
		(color 0 0 0 0)
	)
	(junction
		(at 116.205 181.61)
		(diameter 0)
		(color 0 0 0 0)
	)
	(junction
		(at 45.72 212.725)
		(diameter 0)
		(color 0 0 0 0)
	)
	(junction
		(at 73.66 181.61)
		(diameter 0)
		(color 0 0 0 0)
	)
	(junction
		(at 339.725 55.245)
		(diameter 0)
		(color 0 0 0 0)
	)
	(junction
		(at 137.16 153.035)
		(diameter 0)
		(color 0 0 0 0)
	)
	(junction
		(at 106.045 84.455)
		(diameter 0)
		(color 0 0 0 0)
	)
	(junction
		(at 330.835 87.63)
		(diameter 0)
		(color 0 0 0 0)
	)
	(junction
		(at 38.735 181.61)
		(diameter 0)
		(color 0 0 0 0)
	)
	(junction
		(at 143.51 212.725)
		(diameter 0)
		(color 0 0 0 0)
	)
	(junction
		(at 116.84 113.665)
		(diameter 0)
		(color 0 0 0 0)
	)
	(junction
		(at 66.675 212.725)
		(diameter 0)
		(color 0 0 0 0)
	)
	(junction
		(at 100.33 113.665)
		(diameter 0)
		(color 0 0 0 0)
	)
	(junction
		(at 123.19 153.035)
		(diameter 0)
		(color 0 0 0 0)
	)
	(junction
		(at 83.185 113.665)
		(diameter 0)
		(color 0 0 0 0)
	)
	(junction
		(at 59.055 238.76)
		(diameter 0)
		(color 0 0 0 0)
	)
	(junction
		(at 122.555 212.725)
		(diameter 0)
		(color 0 0 0 0)
	)
	(junction
		(at 137.16 181.61)
		(diameter 0)
		(color 0 0 0 0)
	)
	(junction
		(at 115.57 212.725)
		(diameter 0)
		(color 0 0 0 0)
	)
	(junction
		(at 130.81 84.455)
		(diameter 0)
		(color 0 0 0 0)
	)
	(junction
		(at 38.735 113.665)
		(diameter 0)
		(color 0 0 0 0)
	)
	(junction
		(at 111.76 59.69)
		(diameter 0)
		(color 0 0 0 0)
	)
	(junction
		(at 38.735 212.725)
		(diameter 0)
		(color 0 0 0 0)
	)
	(junction
		(at 147.32 84.455)
		(diameter 0)
		(color 0 0 0 0)
	)
	(junction
		(at 129.54 212.725)
		(diameter 0)
		(color 0 0 0 0)
	)
	(junction
		(at 99.695 59.69)
		(diameter 0)
		(color 0 0 0 0)
	)
	(junction
		(at 144.145 181.61)
		(diameter 0)
		(color 0 0 0 0)
	)
	(junction
		(at 151.13 153.035)
		(diameter 0)
		(color 0 0 0 0)
	)
	(junction
		(at 337.185 118.745)
		(diameter 0)
		(color 0 0 0 0)
	)
	(junction
		(at 80.645 212.725)
		(diameter 0)
		(color 0 0 0 0)
	)
	(junction
		(at 72.39 84.455)
		(diameter 0)
		(color 0 0 0 0)
	)
	(junction
		(at 89.535 84.455)
		(diameter 0)
		(color 0 0 0 0)
	)
	(junction
		(at 130.175 181.61)
		(diameter 0)
		(color 0 0 0 0)
	)
	(junction
		(at 123.19 181.61)
		(diameter 0)
		(color 0 0 0 0)
	)
	(junction
		(at 80.01 238.76)
		(diameter 0)
		(color 0 0 0 0)
	)
	(junction
		(at 125.095 113.665)
		(diameter 0)
		(color 0 0 0 0)
	)
	(junction
		(at 155.575 84.455)
		(diameter 0)
		(color 0 0 0 0)
	)
	(junction
		(at 64.135 84.455)
		(diameter 0)
		(color 0 0 0 0)
	)
	(junction
		(at 330.2 118.745)
		(diameter 0)
		(color 0 0 0 0)
	)
	(junction
		(at 208.28 95.25)
		(diameter 0)
		(color 0 0 0 0)
	)
	(junction
		(at 120.65 59.69)
		(diameter 0)
		(color 0 0 0 0)
	)
	(junction
		(at 97.79 84.455)
		(diameter 0)
		(color 0 0 0 0)
	)
	(junction
		(at 130.175 153.035)
		(diameter 0)
		(color 0 0 0 0)
	)
	(junction
		(at 57.15 60.325)
		(diameter 0)
		(color 0 0 0 0)
	)
	(junction
		(at 66.04 238.76)
		(diameter 0)
		(color 0 0 0 0)
	)
	(junction
		(at 55.88 113.665)
		(diameter 0)
		(color 0 0 0 0)
	)
	(junction
		(at 359.41 118.745)
		(diameter 0)
		(color 0 0 0 0)
	)
	(junction
		(at 38.735 153.035)
		(diameter 0)
		(color 0 0 0 0)
	)
	(junction
		(at 116.205 153.035)
		(diameter 0)
		(color 0 0 0 0)
	)
	(junction
		(at 144.145 153.035)
		(diameter 0)
		(color 0 0 0 0)
	)
	(junction
		(at 81.28 84.455)
		(diameter 0)
		(color 0 0 0 0)
	)
	(junction
		(at 352.425 118.745)
		(diameter 0)
		(color 0 0 0 0)
	)
	(junction
		(at 55.88 84.455)
		(diameter 0)
		(color 0 0 0 0)
	)
	(junction
		(at 288.925 102.87)
		(diameter 0)
		(color 0 0 0 0)
	)
	(junction
		(at 73.025 238.76)
		(diameter 0)
		(color 0 0 0 0)
	)
	(junction
		(at 150.495 212.725)
		(diameter 0)
		(color 0 0 0 0)
	)
	(wire
		(pts
			(xy 344.805 118.745) (xy 352.425 118.745)
		)
		(stroke
			(width 0)
			(type default)
		)
	)
	(wire
		(pts
			(xy 83.185 113.665) (xy 92.075 113.665)
		)
		(stroke
			(width 0)
			(type default)
		)
	)
	(wire
		(pts
			(xy 99.695 59.69) (xy 99.695 61.595)
		)
		(stroke
			(width 0)
			(type default)
		)
	)
	(wire
		(pts
			(xy 80.645 181.61) (xy 87.63 181.61)
		)
		(stroke
			(width 0)
			(type default)
		)
	)
	(wire
		(pts
			(xy 330.835 95.885) (xy 330.835 94.615)
		)
		(stroke
			(width 0)
			(type default)
		)
	)
	(wire
		(pts
			(xy 141.605 117.475) (xy 141.605 113.665)
		)
		(stroke
			(width 0)
			(type default)
		)
	)
	(polyline
		(pts
			(xy 134.62 58.42) (xy 134.62 67.945)
		)
		(stroke
			(width 0)
			(type dash)
		)
	)
	(wire
		(pts
			(xy 55.88 88.265) (xy 55.88 84.455)
		)
		(stroke
			(width 0)
			(type default)
		)
	)
	(wire
		(pts
			(xy 116.205 184.15) (xy 116.205 181.61)
		)
		(stroke
			(width 0)
			(type default)
		)
	)
	(wire
		(pts
			(xy 151.13 153.035) (xy 144.145 153.035)
		)
		(stroke
			(width 0)
			(type default)
		)
	)
	(wire
		(pts
			(xy 86.995 248.92) (xy 86.995 247.65)
		)
		(stroke
			(width 0)
			(type default)
		)
	)
	(wire
		(pts
			(xy 114.3 84.455) (xy 122.555 84.455)
		)
		(stroke
			(width 0)
			(type default)
		)
	)
	(wire
		(pts
			(xy 347.98 55.245) (xy 356.235 55.245)
		)
		(stroke
			(width 0)
			(type default)
		)
	)
	(wire
		(pts
			(xy 39.37 68.58) (xy 39.37 67.31)
		)
		(stroke
			(width 0)
			(type default)
		)
	)
	(wire
		(pts
			(xy 83.185 113.665) (xy 83.185 117.475)
		)
		(stroke
			(width 0)
			(type default)
		)
	)
	(wire
		(pts
			(xy 120.65 59.69) (xy 129.54 59.69)
		)
		(stroke
			(width 0)
			(type default)
		)
	)
	(wire
		(pts
			(xy 340.995 87.63) (xy 340.995 89.535)
		)
		(stroke
			(width 0)
			(type default)
		)
	)
	(wire
		(pts
			(xy 288.925 95.25) (xy 293.37 95.25)
		)
		(stroke
			(width 0)
			(type default)
		)
	)
	(wire
		(pts
			(xy 72.39 88.265) (xy 72.39 84.455)
		)
		(stroke
			(width 0)
			(type default)
		)
	)
	(polyline
		(pts
			(xy 328.93 53.975) (xy 328.93 62.865)
		)
		(stroke
			(width 0)
			(type dash)
		)
	)
	(wire
		(pts
			(xy 137.16 191.135) (xy 137.16 189.23)
		)
		(stroke
			(width 0)
			(type default)
		)
	)
	(wire
		(pts
			(xy 106.045 94.615) (xy 106.045 93.345)
		)
		(stroke
			(width 0)
			(type default)
		)
	)
	(polyline
		(pts
			(xy 113.03 213.995) (xy 120.015 213.995)
		)
		(stroke
			(width 0)
			(type dash)
		)
	)
	(wire
		(pts
			(xy 73.66 220.98) (xy 73.66 219.71)
		)
		(stroke
			(width 0)
			(type default)
		)
	)
	(wire
		(pts
			(xy 57.15 60.325) (xy 72.39 60.325)
		)
		(stroke
			(width 0)
			(type default)
		)
	)
	(wire
		(pts
			(xy 139.065 94.615) (xy 139.065 93.345)
		)
		(stroke
			(width 0)
			(type default)
		)
	)
	(wire
		(pts
			(xy 163.83 84.455) (xy 172.085 84.455)
		)
		(stroke
			(width 0)
			(type default)
		)
	)
	(wire
		(pts
			(xy 55.88 113.665) (xy 64.135 113.665)
		)
		(stroke
			(width 0)
			(type default)
		)
	)
	(wire
		(pts
			(xy 340.995 95.885) (xy 340.995 94.615)
		)
		(stroke
			(width 0)
			(type default)
		)
	)
	(polyline
		(pts
			(xy 36.195 213.995) (xy 36.195 220.98)
		)
		(stroke
			(width 0)
			(type dash)
		)
	)
	(wire
		(pts
			(xy 66.675 214.63) (xy 66.675 212.725)
		)
		(stroke
			(width 0)
			(type default)
		)
	)
	(wire
		(pts
			(xy 123.19 153.035) (xy 116.205 153.035)
		)
		(stroke
			(width 0)
			(type default)
		)
	)
	(wire
		(pts
			(xy 73.025 242.57) (xy 73.025 238.76)
		)
		(stroke
			(width 0)
			(type default)
		)
	)
	(polyline
		(pts
			(xy 97.155 58.42) (xy 97.155 67.945)
		)
		(stroke
			(width 0)
			(type dash)
		)
	)
	(wire
		(pts
			(xy 151.13 155.575) (xy 151.13 153.035)
		)
		(stroke
			(width 0)
			(type default)
		)
	)
	(wire
		(pts
			(xy 330.2 127) (xy 330.2 125.73)
		)
		(stroke
			(width 0)
			(type default)
		)
	)
	(wire
		(pts
			(xy 38.1 248.92) (xy 38.1 247.65)
		)
		(stroke
			(width 0)
			(type default)
		)
	)
	(wire
		(pts
			(xy 241.3 90.17) (xy 238.76 90.17)
		)
		(stroke
			(width 0)
			(type default)
		)
	)
	(wire
		(pts
			(xy 46.99 113.665) (xy 55.88 113.665)
		)
		(stroke
			(width 0)
			(type default)
		)
	)
	(polyline
		(pts
			(xy 43.18 213.995) (xy 43.18 220.98)
		)
		(stroke
			(width 0)
			(type dash)
		)
	)
	(wire
		(pts
			(xy 293.37 95.25) (xy 293.37 96.52)
		)
		(stroke
			(width 0)
			(type default)
		)
	)
	(wire
		(pts
			(xy 330.2 118.745) (xy 337.185 118.745)
		)
		(stroke
			(width 0)
			(type default)
		)
	)
	(wire
		(pts
			(xy 208.28 87.63) (xy 238.76 87.63)
		)
		(stroke
			(width 0)
			(type default)
		)
	)
	(wire
		(pts
			(xy 339.725 55.245) (xy 339.725 57.15)
		)
		(stroke
			(width 0)
			(type default)
		)
	)
	(polyline
		(pts
			(xy 113.665 182.88) (xy 113.665 189.865)
		)
		(stroke
			(width 0)
			(type dash)
		)
	)
	(wire
		(pts
			(xy 123.19 184.15) (xy 123.19 181.61)
		)
		(stroke
			(width 0)
			(type default)
		)
	)
	(wire
		(pts
			(xy 72.39 84.455) (xy 81.28 84.455)
		)
		(stroke
			(width 0)
			(type default)
		)
	)
	(wire
		(pts
			(xy 111.76 59.69) (xy 111.76 62.23)
		)
		(stroke
			(width 0)
			(type default)
		)
	)
	(wire
		(pts
			(xy 293.37 95.25) (xy 311.15 95.25)
		)
		(stroke
			(width 0)
			(type default)
		)
	)
	(polyline
		(pts
			(xy 120.015 213.995) (xy 120.015 220.98)
		)
		(stroke
			(width 0)
			(type dash)
		)
	)
	(wire
		(pts
			(xy 80.645 212.725) (xy 73.66 212.725)
		)
		(stroke
			(width 0)
			(type default)
		)
	)
	(wire
		(pts
			(xy 116.205 151.765) (xy 116.205 153.035)
		)
		(stroke
			(width 0)
			(type default)
		)
	)
	(wire
		(pts
			(xy 356.235 63.5) (xy 356.235 62.23)
		)
		(stroke
			(width 0)
			(type default)
		)
	)
	(wire
		(pts
			(xy 106.045 88.265) (xy 106.045 84.455)
		)
		(stroke
			(width 0)
			(type default)
		)
	)
	(wire
		(pts
			(xy 52.07 238.76) (xy 45.085 238.76)
		)
		(stroke
			(width 0)
			(type default)
		)
	)
	(wire
		(pts
			(xy 45.72 153.035) (xy 38.735 153.035)
		)
		(stroke
			(width 0)
			(type default)
		)
	)
	(wire
		(pts
			(xy 39.37 59.055) (xy 39.37 60.325)
		)
		(stroke
			(width 0)
			(type default)
		)
	)
	(wire
		(pts
			(xy 87.63 190.5) (xy 87.63 189.23)
		)
		(stroke
			(width 0)
			(type default)
		)
	)
	(wire
		(pts
			(xy 130.175 155.575) (xy 130.175 153.035)
		)
		(stroke
			(width 0)
			(type default)
		)
	)
	(wire
		(pts
			(xy 73.66 190.5) (xy 73.66 189.23)
		)
		(stroke
			(width 0)
			(type default)
		)
	)
	(polyline
		(pts
			(xy 36.195 213.995) (xy 43.18 213.995)
		)
		(stroke
			(width 0)
			(type dash)
		)
	)
	(wire
		(pts
			(xy 130.175 162.56) (xy 130.175 160.655)
		)
		(stroke
			(width 0)
			(type default)
		)
	)
	(wire
		(pts
			(xy 38.735 211.455) (xy 38.735 212.725)
		)
		(stroke
			(width 0)
			(type default)
		)
	)
	(wire
		(pts
			(xy 81.28 94.615) (xy 81.28 93.345)
		)
		(stroke
			(width 0)
			(type default)
		)
	)
	(wire
		(pts
			(xy 111.76 68.58) (xy 111.76 67.31)
		)
		(stroke
			(width 0)
			(type default)
		)
	)
	(wire
		(pts
			(xy 59.69 212.725) (xy 52.705 212.725)
		)
		(stroke
			(width 0)
			(type default)
		)
	)
	(wire
		(pts
			(xy 59.69 181.61) (xy 52.705 181.61)
		)
		(stroke
			(width 0)
			(type default)
		)
	)
	(wire
		(pts
			(xy 39.37 94.615) (xy 39.37 93.345)
		)
		(stroke
			(width 0)
			(type default)
		)
	)
	(wire
		(pts
			(xy 238.76 87.63) (xy 241.3 87.63)
		)
		(stroke
			(width 0)
			(type default)
		)
	)
	(wire
		(pts
			(xy 285.75 97.79) (xy 288.925 97.79)
		)
		(stroke
			(width 0)
			(type default)
		)
	)
	(wire
		(pts
			(xy 45.72 184.15) (xy 45.72 181.61)
		)
		(stroke
			(width 0)
			(type default)
		)
	)
	(wire
		(pts
			(xy 66.675 212.725) (xy 59.69 212.725)
		)
		(stroke
			(width 0)
			(type default)
		)
	)
	(wire
		(pts
			(xy 158.115 155.575) (xy 158.115 153.035)
		)
		(stroke
			(width 0)
			(type default)
		)
	)
	(polyline
		(pts
			(xy 113.665 154.305) (xy 120.65 154.305)
		)
		(stroke
			(width 0)
			(type dash)
		)
	)
	(wire
		(pts
			(xy 45.085 238.76) (xy 38.1 238.76)
		)
		(stroke
			(width 0)
			(type default)
		)
	)
	(wire
		(pts
			(xy 64.135 94.615) (xy 64.135 93.345)
		)
		(stroke
			(width 0)
			(type default)
		)
	)
	(wire
		(pts
			(xy 64.135 124.46) (xy 64.135 122.555)
		)
		(stroke
			(width 0)
			(type default)
		)
	)
	(wire
		(pts
			(xy 130.81 84.455) (xy 139.065 84.455)
		)
		(stroke
			(width 0)
			(type default)
		)
	)
	(wire
		(pts
			(xy 344.805 127) (xy 344.805 125.73)
		)
		(stroke
			(width 0)
			(type default)
		)
	)
	(polyline
		(pts
			(xy 97.155 58.42) (xy 134.62 58.42)
		)
		(stroke
			(width 0)
			(type dash)
		)
	)
	(wire
		(pts
			(xy 158.115 153.035) (xy 151.13 153.035)
		)
		(stroke
			(width 0)
			(type default)
		)
	)
	(wire
		(pts
			(xy 80.01 238.76) (xy 86.995 238.76)
		)
		(stroke
			(width 0)
			(type default)
		)
	)
	(polyline
		(pts
			(xy 120.65 154.305) (xy 120.65 161.29)
		)
		(stroke
			(width 0)
			(type dash)
		)
	)
	(wire
		(pts
			(xy 130.81 94.615) (xy 130.81 93.345)
		)
		(stroke
			(width 0)
			(type default)
		)
	)
	(wire
		(pts
			(xy 39.37 60.325) (xy 39.37 62.23)
		)
		(stroke
			(width 0)
			(type default)
		)
	)
	(wire
		(pts
			(xy 114.3 88.265) (xy 114.3 84.455)
		)
		(stroke
			(width 0)
			(type default)
		)
	)
	(wire
		(pts
			(xy 311.15 92.71) (xy 311.15 80.645)
		)
		(stroke
			(width 0)
			(type default)
		)
	)
	(wire
		(pts
			(xy 59.055 238.76) (xy 52.07 238.76)
		)
		(stroke
			(width 0)
			(type default)
		)
	)
	(wire
		(pts
			(xy 116.205 180.34) (xy 116.205 181.61)
		)
		(stroke
			(width 0)
			(type default)
		)
	)
	(wire
		(pts
			(xy 100.33 113.665) (xy 108.585 113.665)
		)
		(stroke
			(width 0)
			(type default)
		)
	)
	(wire
		(pts
			(xy 144.145 155.575) (xy 144.145 153.035)
		)
		(stroke
			(width 0)
			(type default)
		)
	)
	(wire
		(pts
			(xy 92.075 113.665) (xy 92.075 117.475)
		)
		(stroke
			(width 0)
			(type default)
		)
	)
	(wire
		(pts
			(xy 143.51 212.725) (xy 136.525 212.725)
		)
		(stroke
			(width 0)
			(type default)
		)
	)
	(wire
		(pts
			(xy 97.79 84.455) (xy 106.045 84.455)
		)
		(stroke
			(width 0)
			(type default)
		)
	)
	(wire
		(pts
			(xy 150.495 215.265) (xy 150.495 212.725)
		)
		(stroke
			(width 0)
			(type default)
		)
	)
	(polyline
		(pts
			(xy 36.195 182.88) (xy 43.18 182.88)
		)
		(stroke
			(width 0)
			(type dash)
		)
	)
	(wire
		(pts
			(xy 66.04 248.92) (xy 66.04 247.65)
		)
		(stroke
			(width 0)
			(type default)
		)
	)
	(wire
		(pts
			(xy 38.1 237.49) (xy 38.1 238.76)
		)
		(stroke
			(width 0)
			(type default)
		)
	)
	(polyline
		(pts
			(xy 113.665 154.305) (xy 113.665 161.29)
		)
		(stroke
			(width 0)
			(type dash)
		)
	)
	(wire
		(pts
			(xy 151.13 191.135) (xy 151.13 189.23)
		)
		(stroke
			(width 0)
			(type default)
		)
	)
	(wire
		(pts
			(xy 293.37 102.87) (xy 293.37 101.6)
		)
		(stroke
			(width 0)
			(type default)
		)
	)
	(wire
		(pts
			(xy 288.925 102.87) (xy 293.37 102.87)
		)
		(stroke
			(width 0)
			(type default)
		)
	)
	(wire
		(pts
			(xy 39.37 84.455) (xy 47.625 84.455)
		)
		(stroke
			(width 0)
			(type default)
		)
	)
	(wire
		(pts
			(xy 158.115 162.56) (xy 158.115 160.655)
		)
		(stroke
			(width 0)
			(type default)
		)
	)
	(polyline
		(pts
			(xy 36.195 182.88) (xy 36.195 189.865)
		)
		(stroke
			(width 0)
			(type dash)
		)
	)
	(wire
		(pts
			(xy 99.695 59.69) (xy 111.76 59.69)
		)
		(stroke
			(width 0)
			(type default)
		)
	)
	(wire
		(pts
			(xy 116.84 117.475) (xy 116.84 113.665)
		)
		(stroke
			(width 0)
			(type default)
		)
	)
	(wire
		(pts
			(xy 52.705 212.725) (xy 45.72 212.725)
		)
		(stroke
			(width 0)
			(type default)
		)
	)
	(wire
		(pts
			(xy 130.175 191.135) (xy 130.175 189.23)
		)
		(stroke
			(width 0)
			(type default)
		)
	)
	(wire
		(pts
			(xy 157.48 215.265) (xy 157.48 212.725)
		)
		(stroke
			(width 0)
			(type default)
		)
	)
	(wire
		(pts
			(xy 52.705 181.61) (xy 45.72 181.61)
		)
		(stroke
			(width 0)
			(type default)
		)
	)
	(polyline
		(pts
			(xy 43.18 241.935) (xy 43.18 248.92)
		)
		(stroke
			(width 0)
			(type dash)
		)
	)
	(wire
		(pts
			(xy 337.185 120.65) (xy 337.185 118.745)
		)
		(stroke
			(width 0)
			(type default)
		)
	)
	(wire
		(pts
			(xy 89.535 94.615) (xy 89.535 93.345)
		)
		(stroke
			(width 0)
			(type default)
		)
	)
	(polyline
		(pts
			(xy 120.015 220.98) (xy 113.03 220.98)
		)
		(stroke
			(width 0)
			(type dash)
		)
	)
	(wire
		(pts
			(xy 45.72 190.5) (xy 45.72 189.23)
		)
		(stroke
			(width 0)
			(type default)
		)
	)
	(wire
		(pts
			(xy 288.29 80.645) (xy 288.29 82.55)
		)
		(stroke
			(width 0)
			(type default)
		)
	)
	(wire
		(pts
			(xy 133.35 124.46) (xy 133.35 122.555)
		)
		(stroke
			(width 0)
			(type default)
		)
	)
	(wire
		(pts
			(xy 46.99 123.825) (xy 46.99 121.92)
		)
		(stroke
			(width 0)
			(type default)
		)
	)
	(polyline
		(pts
			(xy 37.465 113.03) (xy 97.155 113.03)
		)
		(stroke
			(width 0)
			(type dash)
		)
	)
	(wire
		(pts
			(xy 92.075 113.665) (xy 100.33 113.665)
		)
		(stroke
			(width 0)
			(type default)
		)
	)
	(wire
		(pts
			(xy 38.735 220.98) (xy 38.735 219.71)
		)
		(stroke
			(width 0)
			(type default)
		)
	)
	(wire
		(pts
			(xy 155.575 94.615) (xy 155.575 93.345)
		)
		(stroke
			(width 0)
			(type default)
		)
	)
	(wire
		(pts
			(xy 45.72 212.725) (xy 38.735 212.725)
		)
		(stroke
			(width 0)
			(type default)
		)
	)
	(wire
		(pts
			(xy 122.555 88.265) (xy 122.555 84.455)
		)
		(stroke
			(width 0)
			(type default)
		)
	)
	(wire
		(pts
			(xy 130.175 184.15) (xy 130.175 181.61)
		)
		(stroke
			(width 0)
			(type default)
		)
	)
	(wire
		(pts
			(xy 99.695 57.785) (xy 99.695 59.69)
		)
		(stroke
			(width 0)
			(type default)
		)
	)
	(wire
		(pts
			(xy 52.705 214.63) (xy 52.705 212.725)
		)
		(stroke
			(width 0)
			(type default)
		)
	)
	(wire
		(pts
			(xy 47.625 94.615) (xy 47.625 93.345)
		)
		(stroke
			(width 0)
			(type default)
		)
	)
	(wire
		(pts
			(xy 130.81 88.265) (xy 130.81 84.455)
		)
		(stroke
			(width 0)
			(type default)
		)
	)
	(wire
		(pts
			(xy 367.03 118.745) (xy 367.03 120.65)
		)
		(stroke
			(width 0)
			(type default)
		)
	)
	(wire
		(pts
			(xy 38.735 180.34) (xy 38.735 181.61)
		)
		(stroke
			(width 0)
			(type default)
		)
	)
	(wire
		(pts
			(xy 97.79 94.615) (xy 97.79 93.345)
		)
		(stroke
			(width 0)
			(type default)
		)
	)
	(wire
		(pts
			(xy 238.76 90.17) (xy 238.76 87.63)
		)
		(stroke
			(width 0)
			(type default)
		)
	)
	(wire
		(pts
			(xy 137.16 162.56) (xy 137.16 160.655)
		)
		(stroke
			(width 0)
			(type default)
		)
	)
	(wire
		(pts
			(xy 81.28 84.455) (xy 89.535 84.455)
		)
		(stroke
			(width 0)
			(type default)
		)
	)
	(wire
		(pts
			(xy 288.925 103.505) (xy 288.925 102.87)
		)
		(stroke
			(width 0)
			(type default)
		)
	)
	(wire
		(pts
			(xy 73.66 214.63) (xy 73.66 212.725)
		)
		(stroke
			(width 0)
			(type default)
		)
	)
	(wire
		(pts
			(xy 155.575 88.265) (xy 155.575 84.455)
		)
		(stroke
			(width 0)
			(type default)
		)
	)
	(wire
		(pts
			(xy 87.63 214.63) (xy 87.63 212.725)
		)
		(stroke
			(width 0)
			(type default)
		)
	)
	(polyline
		(pts
			(xy 43.815 161.29) (xy 36.83 161.29)
		)
		(stroke
			(width 0)
			(type dash)
		)
	)
	(wire
		(pts
			(xy 89.535 88.265) (xy 89.535 84.455)
		)
		(stroke
			(width 0)
			(type default)
		)
	)
	(wire
		(pts
			(xy 64.135 84.455) (xy 72.39 84.455)
		)
		(stroke
			(width 0)
			(type default)
		)
	)
	(wire
		(pts
			(xy 38.735 190.5) (xy 38.735 189.23)
		)
		(stroke
			(width 0)
			(type default)
		)
	)
	(wire
		(pts
			(xy 311.15 95.25) (xy 311.15 92.71)
		)
		(stroke
			(width 0)
			(type default)
		)
	)
	(wire
		(pts
			(xy 331.47 53.34) (xy 331.47 55.245)
		)
		(stroke
			(width 0)
			(type default)
		)
	)
	(wire
		(pts
			(xy 239.395 80.01) (xy 239.395 82.55)
		)
		(stroke
			(width 0)
			(type default)
		)
	)
	(polyline
		(pts
			(xy 97.155 123.19) (xy 36.195 123.19)
		)
		(stroke
			(width 0)
			(type dash)
		)
	)
	(wire
		(pts
			(xy 359.41 120.65) (xy 359.41 118.745)
		)
		(stroke
			(width 0)
			(type default)
		)
	)
	(wire
		(pts
			(xy 38.735 113.665) (xy 38.735 116.84)
		)
		(stroke
			(width 0)
			(type default)
		)
	)
	(wire
		(pts
			(xy 55.88 124.46) (xy 55.88 122.555)
		)
		(stroke
			(width 0)
			(type default)
		)
	)
	(wire
		(pts
			(xy 80.01 248.92) (xy 80.01 247.65)
		)
		(stroke
			(width 0)
			(type default)
		)
	)
	(wire
		(pts
			(xy 151.13 184.15) (xy 151.13 181.61)
		)
		(stroke
			(width 0)
			(type default)
		)
	)
	(wire
		(pts
			(xy 39.37 83.185) (xy 39.37 84.455)
		)
		(stroke
			(width 0)
			(type default)
		)
	)
	(wire
		(pts
			(xy 215.265 107.95) (xy 241.3 107.95)
		)
		(stroke
			(width 0)
			(type default)
		)
	)
	(wire
		(pts
			(xy 147.32 84.455) (xy 155.575 84.455)
		)
		(stroke
			(width 0)
			(type default)
		)
	)
	(wire
		(pts
			(xy 73.66 113.665) (xy 73.66 117.475)
		)
		(stroke
			(width 0)
			(type default)
		)
	)
	(wire
		(pts
			(xy 129.54 62.23) (xy 129.54 59.69)
		)
		(stroke
			(width 0)
			(type default)
		)
	)
	(wire
		(pts
			(xy 147.32 88.265) (xy 147.32 84.455)
		)
		(stroke
			(width 0)
			(type default)
		)
	)
	(wire
		(pts
			(xy 129.54 222.25) (xy 129.54 220.345)
		)
		(stroke
			(width 0)
			(type default)
		)
	)
	(wire
		(pts
			(xy 238.76 113.03) (xy 238.76 114.935)
		)
		(stroke
			(width 0)
			(type default)
		)
	)
	(wire
		(pts
			(xy 64.135 88.265) (xy 64.135 84.455)
		)
		(stroke
			(width 0)
			(type default)
		)
	)
	(wire
		(pts
			(xy 122.555 222.25) (xy 122.555 220.345)
		)
		(stroke
			(width 0)
			(type default)
		)
	)
	(wire
		(pts
			(xy 157.48 212.725) (xy 150.495 212.725)
		)
		(stroke
			(width 0)
			(type default)
		)
	)
	(wire
		(pts
			(xy 59.69 184.15) (xy 59.69 181.61)
		)
		(stroke
			(width 0)
			(type default)
		)
	)
	(wire
		(pts
			(xy 47.625 84.455) (xy 55.88 84.455)
		)
		(stroke
			(width 0)
			(type default)
		)
	)
	(wire
		(pts
			(xy 80.645 184.15) (xy 80.645 181.61)
		)
		(stroke
			(width 0)
			(type default)
		)
	)
	(polyline
		(pts
			(xy 350.52 126.365) (xy 327.66 126.365)
		)
		(stroke
			(width 0)
			(type dash)
		)
	)
	(wire
		(pts
			(xy 356.235 55.245) (xy 356.235 57.15)
		)
		(stroke
			(width 0)
			(type default)
		)
	)
	(wire
		(pts
			(xy 122.555 84.455) (xy 130.81 84.455)
		)
		(stroke
			(width 0)
			(type default)
		)
	)
	(wire
		(pts
			(xy 331.47 63.5) (xy 331.47 62.23)
		)
		(stroke
			(width 0)
			(type default)
		)
	)
	(wire
		(pts
			(xy 139.065 84.455) (xy 147.32 84.455)
		)
		(stroke
			(width 0)
			(type default)
		)
	)
	(wire
		(pts
			(xy 130.175 181.61) (xy 123.19 181.61)
		)
		(stroke
			(width 0)
			(type default)
		)
	)
	(wire
		(pts
			(xy 337.185 127) (xy 337.185 125.73)
		)
		(stroke
			(width 0)
			(type default)
		)
	)
	(wire
		(pts
			(xy 108.585 113.665) (xy 116.84 113.665)
		)
		(stroke
			(width 0)
			(type default)
		)
	)
	(wire
		(pts
			(xy 45.085 242.57) (xy 45.085 238.76)
		)
		(stroke
			(width 0)
			(type default)
		)
	)
	(wire
		(pts
			(xy 73.66 212.725) (xy 66.675 212.725)
		)
		(stroke
			(width 0)
			(type default)
		)
	)
	(wire
		(pts
			(xy 347.98 63.5) (xy 347.98 62.23)
		)
		(stroke
			(width 0)
			(type default)
		)
	)
	(wire
		(pts
			(xy 359.41 127) (xy 359.41 125.73)
		)
		(stroke
			(width 0)
			(type default)
		)
	)
	(wire
		(pts
			(xy 73.66 181.61) (xy 66.675 181.61)
		)
		(stroke
			(width 0)
			(type default)
		)
	)
	(wire
		(pts
			(xy 53.975 161.925) (xy 53.975 160.02)
		)
		(stroke
			(width 0)
			(type default)
		)
	)
	(wire
		(pts
			(xy 115.57 211.455) (xy 115.57 212.725)
		)
		(stroke
			(width 0)
			(type default)
		)
	)
	(wire
		(pts
			(xy 359.41 118.745) (xy 367.03 118.745)
		)
		(stroke
			(width 0)
			(type default)
		)
	)
	(wire
		(pts
			(xy 299.72 87.63) (xy 299.72 81.915)
		)
		(stroke
			(width 0)
			(type default)
		)
	)
	(wire
		(pts
			(xy 123.19 155.575) (xy 123.19 153.035)
		)
		(stroke
			(width 0)
			(type default)
		)
	)
	(wire
		(pts
			(xy 136.525 222.25) (xy 136.525 220.345)
		)
		(stroke
			(width 0)
			(type default)
		)
	)
	(wire
		(pts
			(xy 330.835 87.63) (xy 330.835 89.535)
		)
		(stroke
			(width 0)
			(type default)
		)
	)
	(wire
		(pts
			(xy 45.72 181.61) (xy 38.735 181.61)
		)
		(stroke
			(width 0)
			(type default)
		)
	)
	(wire
		(pts
			(xy 157.48 222.25) (xy 157.48 220.345)
		)
		(stroke
			(width 0)
			(type default)
		)
	)
	(wire
		(pts
			(xy 241.3 82.55) (xy 239.395 82.55)
		)
		(stroke
			(width 0)
			(type default)
		)
	)
	(wire
		(pts
			(xy 339.725 63.5) (xy 339.725 62.23)
		)
		(stroke
			(width 0)
			(type default)
		)
	)
	(polyline
		(pts
			(xy 43.18 189.865) (xy 36.195 189.865)
		)
		(stroke
			(width 0)
			(type dash)
		)
	)
	(wire
		(pts
			(xy 55.88 117.475) (xy 55.88 113.665)
		)
		(stroke
			(width 0)
			(type default)
		)
	)
	(wire
		(pts
			(xy 66.04 242.57) (xy 66.04 238.76)
		)
		(stroke
			(width 0)
			(type default)
		)
	)
	(polyline
		(pts
			(xy 120.65 161.29) (xy 113.665 161.29)
		)
		(stroke
			(width 0)
			(type dash)
		)
	)
	(wire
		(pts
			(xy 59.055 248.92) (xy 59.055 247.65)
		)
		(stroke
			(width 0)
			(type default)
		)
	)
	(wire
		(pts
			(xy 66.675 181.61) (xy 59.69 181.61)
		)
		(stroke
			(width 0)
			(type default)
		)
	)
	(wire
		(pts
			(xy 57.15 60.325) (xy 57.15 62.23)
		)
		(stroke
			(width 0)
			(type default)
		)
	)
	(wire
		(pts
			(xy 133.35 117.475) (xy 133.35 113.665)
		)
		(stroke
			(width 0)
			(type default)
		)
	)
	(polyline
		(pts
			(xy 350.52 117.475) (xy 350.52 126.365)
		)
		(stroke
			(width 0)
			(type dash)
		)
	)
	(wire
		(pts
			(xy 330.835 86.36) (xy 330.835 87.63)
		)
		(stroke
			(width 0)
			(type default)
		)
	)
	(wire
		(pts
			(xy 208.28 81.28) (xy 208.28 87.63)
		)
		(stroke
			(width 0)
			(type default)
		)
	)
	(wire
		(pts
			(xy 158.115 184.15) (xy 158.115 181.61)
		)
		(stroke
			(width 0)
			(type default)
		)
	)
	(wire
		(pts
			(xy 330.2 118.745) (xy 330.2 120.65)
		)
		(stroke
			(width 0)
			(type default)
		)
	)
	(wire
		(pts
			(xy 367.03 127) (xy 367.03 125.73)
		)
		(stroke
			(width 0)
			(type default)
		)
	)
	(wire
		(pts
			(xy 130.175 153.035) (xy 123.19 153.035)
		)
		(stroke
			(width 0)
			(type default)
		)
	)
	(wire
		(pts
			(xy 123.19 162.56) (xy 123.19 160.655)
		)
		(stroke
			(width 0)
			(type default)
		)
	)
	(wire
		(pts
			(xy 80.645 181.61) (xy 73.66 181.61)
		)
		(stroke
			(width 0)
			(type default)
		)
	)
	(wire
		(pts
			(xy 72.39 94.615) (xy 72.39 93.345)
		)
		(stroke
			(width 0)
			(type default)
		)
	)
	(wire
		(pts
			(xy 208.28 87.63) (xy 208.28 95.25)
		)
		(stroke
			(width 0)
			(type default)
		)
	)
	(wire
		(pts
			(xy 122.555 215.265) (xy 122.555 212.725)
		)
		(stroke
			(width 0)
			(type default)
		)
	)
	(wire
		(pts
			(xy 238.76 113.03) (xy 241.3 113.03)
		)
		(stroke
			(width 0)
			(type default)
		)
	)
	(wire
		(pts
			(xy 73.025 248.92) (xy 73.025 247.65)
		)
		(stroke
			(width 0)
			(type default)
		)
	)
	(wire
		(pts
			(xy 116.84 124.46) (xy 116.84 122.555)
		)
		(stroke
			(width 0)
			(type default)
		)
	)
	(wire
		(pts
			(xy 80.01 242.57) (xy 80.01 238.76)
		)
		(stroke
			(width 0)
			(type default)
		)
	)
	(wire
		(pts
			(xy 39.37 60.325) (xy 57.15 60.325)
		)
		(stroke
			(width 0)
			(type default)
		)
	)
	(polyline
		(pts
			(xy 36.83 154.305) (xy 36.83 161.29)
		)
		(stroke
			(width 0)
			(type dash)
		)
	)
	(polyline
		(pts
			(xy 353.695 62.865) (xy 328.93 62.865)
		)
		(stroke
			(width 0)
			(type dash)
		)
	)
	(wire
		(pts
			(xy 73.66 184.15) (xy 73.66 181.61)
		)
		(stroke
			(width 0)
			(type default)
		)
	)
	(wire
		(pts
			(xy 80.645 212.725) (xy 87.63 212.725)
		)
		(stroke
			(width 0)
			(type default)
		)
	)
	(polyline
		(pts
			(xy 36.195 241.935) (xy 43.18 241.935)
		)
		(stroke
			(width 0)
			(type dash)
		)
	)
	(wire
		(pts
			(xy 172.085 94.615) (xy 172.085 93.345)
		)
		(stroke
			(width 0)
			(type default)
		)
	)
	(wire
		(pts
			(xy 120.65 68.58) (xy 120.65 67.31)
		)
		(stroke
			(width 0)
			(type default)
		)
	)
	(wire
		(pts
			(xy 115.57 215.265) (xy 115.57 212.725)
		)
		(stroke
			(width 0)
			(type default)
		)
	)
	(wire
		(pts
			(xy 73.025 238.76) (xy 66.04 238.76)
		)
		(stroke
			(width 0)
			(type default)
		)
	)
	(wire
		(pts
			(xy 111.76 59.69) (xy 120.65 59.69)
		)
		(stroke
			(width 0)
			(type default)
		)
	)
	(wire
		(pts
			(xy 89.535 84.455) (xy 97.79 84.455)
		)
		(stroke
			(width 0)
			(type default)
		)
	)
	(wire
		(pts
			(xy 364.49 63.5) (xy 364.49 62.23)
		)
		(stroke
			(width 0)
			(type default)
		)
	)
	(wire
		(pts
			(xy 73.66 113.665) (xy 83.185 113.665)
		)
		(stroke
			(width 0)
			(type default)
		)
	)
	(wire
		(pts
			(xy 66.675 190.5) (xy 66.675 189.23)
		)
		(stroke
			(width 0)
			(type default)
		)
	)
	(polyline
		(pts
			(xy 43.815 154.305) (xy 43.815 161.29)
		)
		(stroke
			(width 0)
			(type dash)
		)
	)
	(polyline
		(pts
			(xy 120.65 189.865) (xy 113.665 189.865)
		)
		(stroke
			(width 0)
			(type dash)
		)
	)
	(wire
		(pts
			(xy 352.425 118.745) (xy 359.41 118.745)
		)
		(stroke
			(width 0)
			(type default)
		)
	)
	(wire
		(pts
			(xy 238.76 97.79) (xy 238.76 113.03)
		)
		(stroke
			(width 0)
			(type default)
		)
	)
	(wire
		(pts
			(xy 39.37 88.265) (xy 39.37 84.455)
		)
		(stroke
			(width 0)
			(type default)
		)
	)
	(polyline
		(pts
			(xy 328.93 53.975) (xy 353.695 53.975)
		)
		(stroke
			(width 0)
			(type dash)
		)
	)
	(polyline
		(pts
			(xy 120.65 182.88) (xy 120.65 189.865)
		)
		(stroke
			(width 0)
			(type dash)
		)
	)
	(wire
		(pts
			(xy 45.72 220.98) (xy 45.72 219.71)
		)
		(stroke
			(width 0)
			(type default)
		)
	)
	(wire
		(pts
			(xy 147.32 94.615) (xy 147.32 93.345)
		)
		(stroke
			(width 0)
			(type default)
		)
	)
	(wire
		(pts
			(xy 83.185 124.46) (xy 83.185 122.555)
		)
		(stroke
			(width 0)
			(type default)
		)
	)
	(wire
		(pts
			(xy 129.54 212.725) (xy 122.555 212.725)
		)
		(stroke
			(width 0)
			(type default)
		)
	)
	(polyline
		(pts
			(xy 113.665 182.88) (xy 120.65 182.88)
		)
		(stroke
			(width 0)
			(type dash)
		)
	)
	(wire
		(pts
			(xy 122.555 94.615) (xy 122.555 93.345)
		)
		(stroke
			(width 0)
			(type default)
		)
	)
	(wire
		(pts
			(xy 87.63 184.15) (xy 87.63 181.61)
		)
		(stroke
			(width 0)
			(type default)
		)
	)
	(polyline
		(pts
			(xy 55.245 58.42) (xy 85.725 58.42)
		)
		(stroke
			(width 0)
			(type dash)
		)
	)
	(polyline
		(pts
			(xy 134.62 67.945) (xy 97.155 67.945)
		)
		(stroke
			(width 0)
			(type dash)
		)
	)
	(wire
		(pts
			(xy 288.925 100.33) (xy 288.925 102.87)
		)
		(stroke
			(width 0)
			(type default)
		)
	)
	(wire
		(pts
			(xy 129.54 68.58) (xy 129.54 67.31)
		)
		(stroke
			(width 0)
			(type default)
		)
	)
	(wire
		(pts
			(xy 208.28 95.25) (xy 241.3 95.25)
		)
		(stroke
			(width 0)
			(type default)
		)
	)
	(wire
		(pts
			(xy 125.095 117.475) (xy 125.095 113.665)
		)
		(stroke
			(width 0)
			(type default)
		)
	)
	(wire
		(pts
			(xy 120.65 59.69) (xy 120.65 62.23)
		)
		(stroke
			(width 0)
			(type default)
		)
	)
	(wire
		(pts
			(xy 137.16 155.575) (xy 137.16 153.035)
		)
		(stroke
			(width 0)
			(type default)
		)
	)
	(wire
		(pts
			(xy 144.145 191.135) (xy 144.145 189.23)
		)
		(stroke
			(width 0)
			(type default)
		)
	)
	(wire
		(pts
			(xy 108.585 117.475) (xy 108.585 113.665)
		)
		(stroke
			(width 0)
			(type default)
		)
	)
	(wire
		(pts
			(xy 97.79 88.265) (xy 97.79 84.455)
		)
		(stroke
			(width 0)
			(type default)
		)
	)
	(wire
		(pts
			(xy 106.045 84.455) (xy 114.3 84.455)
		)
		(stroke
			(width 0)
			(type default)
		)
	)
	(wire
		(pts
			(xy 144.145 181.61) (xy 137.16 181.61)
		)
		(stroke
			(width 0)
			(type default)
		)
	)
	(wire
		(pts
			(xy 144.145 162.56) (xy 144.145 160.655)
		)
		(stroke
			(width 0)
			(type default)
		)
	)
	(wire
		(pts
			(xy 80.01 238.76) (xy 73.025 238.76)
		)
		(stroke
			(width 0)
			(type default)
		)
	)
	(wire
		(pts
			(xy 150.495 222.25) (xy 150.495 220.345)
		)
		(stroke
			(width 0)
			(type default)
		)
	)
	(wire
		(pts
			(xy 356.235 55.245) (xy 364.49 55.245)
		)
		(stroke
			(width 0)
			(type default)
		)
	)
	(wire
		(pts
			(xy 288.925 97.79) (xy 288.925 95.25)
		)
		(stroke
			(width 0)
			(type default)
		)
	)
	(wire
		(pts
			(xy 87.63 220.98) (xy 87.63 219.71)
		)
		(stroke
			(width 0)
			(type default)
		)
	)
	(wire
		(pts
			(xy 331.47 55.245) (xy 339.725 55.245)
		)
		(stroke
			(width 0)
			(type default)
		)
	)
	(wire
		(pts
			(xy 133.35 113.665) (xy 141.605 113.665)
		)
		(stroke
			(width 0)
			(type default)
		)
	)
	(wire
		(pts
			(xy 331.47 55.245) (xy 331.47 57.15)
		)
		(stroke
			(width 0)
			(type default)
		)
	)
	(wire
		(pts
			(xy 285.75 92.71) (xy 311.15 92.71)
		)
		(stroke
			(width 0)
			(type default)
		)
	)
	(polyline
		(pts
			(xy 97.155 113.03) (xy 97.155 123.19)
		)
		(stroke
			(width 0)
			(type dash)
		)
	)
	(wire
		(pts
			(xy 116.205 191.135) (xy 116.205 189.23)
		)
		(stroke
			(width 0)
			(type default)
		)
	)
	(wire
		(pts
			(xy 99.695 67.945) (xy 99.695 66.675)
		)
		(stroke
			(width 0)
			(type default)
		)
	)
	(wire
		(pts
			(xy 285.75 100.33) (xy 288.925 100.33)
		)
		(stroke
			(width 0)
			(type default)
		)
	)
	(wire
		(pts
			(xy 151.13 162.56) (xy 151.13 160.655)
		)
		(stroke
			(width 0)
			(type default)
		)
	)
	(wire
		(pts
			(xy 38.735 161.925) (xy 38.735 160.02)
		)
		(stroke
			(width 0)
			(type default)
		)
	)
	(wire
		(pts
			(xy 38.735 113.665) (xy 46.99 113.665)
		)
		(stroke
			(width 0)
			(type default)
		)
	)
	(wire
		(pts
			(xy 64.135 117.475) (xy 64.135 113.665)
		)
		(stroke
			(width 0)
			(type default)
		)
	)
	(wire
		(pts
			(xy 208.28 102.87) (xy 241.3 102.87)
		)
		(stroke
			(width 0)
			(type default)
		)
	)
	(wire
		(pts
			(xy 215.265 81.28) (xy 215.265 107.95)
		)
		(stroke
			(width 0)
			(type default)
		)
	)
	(wire
		(pts
			(xy 330.2 116.84) (xy 330.2 118.745)
		)
		(stroke
			(width 0)
			(type default)
		)
	)
	(wire
		(pts
			(xy 59.69 190.5) (xy 59.69 189.23)
		)
		(stroke
			(width 0)
			(type default)
		)
	)
	(wire
		(pts
			(xy 116.205 162.56) (xy 116.205 160.655)
		)
		(stroke
			(width 0)
			(type default)
		)
	)
	(wire
		(pts
			(xy 72.39 60.325) (xy 72.39 62.23)
		)
		(stroke
			(width 0)
			(type default)
		)
	)
	(wire
		(pts
			(xy 116.84 113.665) (xy 125.095 113.665)
		)
		(stroke
			(width 0)
			(type default)
		)
	)
	(wire
		(pts
			(xy 114.3 94.615) (xy 114.3 93.345)
		)
		(stroke
			(width 0)
			(type default)
		)
	)
	(wire
		(pts
			(xy 137.16 184.15) (xy 137.16 181.61)
		)
		(stroke
			(width 0)
			(type default)
		)
	)
	(wire
		(pts
			(xy 46.99 113.665) (xy 46.99 116.84)
		)
		(stroke
			(width 0)
			(type default)
		)
	)
	(wire
		(pts
			(xy 352.425 118.745) (xy 352.425 120.65)
		)
		(stroke
			(width 0)
			(type default)
		)
	)
	(wire
		(pts
			(xy 100.33 124.46) (xy 100.33 122.555)
		)
		(stroke
			(width 0)
			(type default)
		)
	)
	(wire
		(pts
			(xy 100.33 117.475) (xy 100.33 113.665)
		)
		(stroke
			(width 0)
			(type default)
		)
	)
	(wire
		(pts
			(xy 81.28 88.265) (xy 81.28 84.455)
		)
		(stroke
			(width 0)
			(type default)
		)
	)
	(polyline
		(pts
			(xy 36.195 241.935) (xy 36.195 248.92)
		)
		(stroke
			(width 0)
			(type dash)
		)
	)
	(polyline
		(pts
			(xy 43.18 248.92) (xy 36.195 248.92)
		)
		(stroke
			(width 0)
			(type dash)
		)
	)
	(wire
		(pts
			(xy 337.185 118.745) (xy 344.805 118.745)
		)
		(stroke
			(width 0)
			(type default)
		)
	)
	(polyline
		(pts
			(xy 43.18 182.88) (xy 43.18 189.865)
		)
		(stroke
			(width 0)
			(type dash)
		)
	)
	(wire
		(pts
			(xy 125.095 113.665) (xy 133.35 113.665)
		)
		(stroke
			(width 0)
			(type default)
		)
	)
	(polyline
		(pts
			(xy 55.245 67.945) (xy 85.725 67.945)
		)
		(stroke
			(width 0)
			(type dash)
		)
	)
	(wire
		(pts
			(xy 155.575 84.455) (xy 163.83 84.455)
		)
		(stroke
			(width 0)
			(type default)
		)
	)
	(wire
		(pts
			(xy 55.88 84.455) (xy 64.135 84.455)
		)
		(stroke
			(width 0)
			(type default)
		)
	)
	(polyline
		(pts
			(xy 327.66 117.475) (xy 350.52 117.475)
		)
		(stroke
			(width 0)
			(type dash)
		)
	)
	(wire
		(pts
			(xy 129.54 215.265) (xy 129.54 212.725)
		)
		(stroke
			(width 0)
			(type default)
		)
	)
	(wire
		(pts
			(xy 59.055 242.57) (xy 59.055 238.76)
		)
		(stroke
			(width 0)
			(type default)
		)
	)
	(wire
		(pts
			(xy 45.085 248.92) (xy 45.085 247.65)
		)
		(stroke
			(width 0)
			(type default)
		)
	)
	(wire
		(pts
			(xy 347.98 57.15) (xy 347.98 55.245)
		)
		(stroke
			(width 0)
			(type default)
		)
	)
	(wire
		(pts
			(xy 163.83 94.615) (xy 163.83 93.345)
		)
		(stroke
			(width 0)
			(type default)
		)
	)
	(wire
		(pts
			(xy 73.66 124.46) (xy 73.66 122.555)
		)
		(stroke
			(width 0)
			(type default)
		)
	)
	(polyline
		(pts
			(xy 36.195 123.19) (xy 36.195 113.03)
		)
		(stroke
			(width 0)
			(type dash)
		)
	)
	(wire
		(pts
			(xy 285.75 82.55) (xy 288.29 82.55)
		)
		(stroke
			(width 0)
			(type default)
		)
	)
	(wire
		(pts
			(xy 144.145 153.035) (xy 137.16 153.035)
		)
		(stroke
			(width 0)
			(type default)
		)
	)
	(wire
		(pts
			(xy 45.72 153.035) (xy 53.975 153.035)
		)
		(stroke
			(width 0)
			(type default)
		)
	)
	(wire
		(pts
			(xy 139.065 88.265) (xy 139.065 84.455)
		)
		(stroke
			(width 0)
			(type default)
		)
	)
	(polyline
		(pts
			(xy 43.18 220.98) (xy 36.195 220.98)
		)
		(stroke
			(width 0)
			(type dash)
		)
	)
	(wire
		(pts
			(xy 38.735 123.825) (xy 38.735 121.92)
		)
		(stroke
			(width 0)
			(type default)
		)
	)
	(wire
		(pts
			(xy 59.69 220.98) (xy 59.69 219.71)
		)
		(stroke
			(width 0)
			(type default)
		)
	)
	(wire
		(pts
			(xy 80.645 190.5) (xy 80.645 189.23)
		)
		(stroke
			(width 0)
			(type default)
		)
	)
	(wire
		(pts
			(xy 66.675 184.15) (xy 66.675 181.61)
		)
		(stroke
			(width 0)
			(type default)
		)
	)
	(wire
		(pts
			(xy 115.57 222.25) (xy 115.57 220.345)
		)
		(stroke
			(width 0)
			(type default)
		)
	)
	(wire
		(pts
			(xy 52.07 248.92) (xy 52.07 247.65)
		)
		(stroke
			(width 0)
			(type default)
		)
	)
	(wire
		(pts
			(xy 150.495 212.725) (xy 143.51 212.725)
		)
		(stroke
			(width 0)
			(type default)
		)
	)
	(wire
		(pts
			(xy 45.72 214.63) (xy 45.72 212.725)
		)
		(stroke
			(width 0)
			(type default)
		)
	)
	(wire
		(pts
			(xy 339.725 55.245) (xy 347.98 55.245)
		)
		(stroke
			(width 0)
			(type default)
		)
	)
	(wire
		(pts
			(xy 136.525 212.725) (xy 129.54 212.725)
		)
		(stroke
			(width 0)
			(type default)
		)
	)
	(wire
		(pts
			(xy 38.735 214.63) (xy 38.735 212.725)
		)
		(stroke
			(width 0)
			(type default)
		)
	)
	(wire
		(pts
			(xy 136.525 215.265) (xy 136.525 212.725)
		)
		(stroke
			(width 0)
			(type default)
		)
	)
	(wire
		(pts
			(xy 144.145 184.15) (xy 144.145 181.61)
		)
		(stroke
			(width 0)
			(type default)
		)
	)
	(wire
		(pts
			(xy 123.19 191.135) (xy 123.19 189.23)
		)
		(stroke
			(width 0)
			(type default)
		)
	)
	(wire
		(pts
			(xy 352.425 127) (xy 352.425 125.73)
		)
		(stroke
			(width 0)
			(type default)
		)
	)
	(polyline
		(pts
			(xy 55.245 58.42) (xy 55.245 67.945)
		)
		(stroke
			(width 0)
			(type dash)
		)
	)
	(polyline
		(pts
			(xy 191.135 283.845) (xy 191.77 283.845)
		)
		(stroke
			(width 0)
			(type default)
		)
	)
	(wire
		(pts
			(xy 53.975 154.94) (xy 53.975 153.035)
		)
		(stroke
			(width 0)
			(type default)
		)
	)
	(wire
		(pts
			(xy 64.135 113.665) (xy 73.66 113.665)
		)
		(stroke
			(width 0)
			(type default)
		)
	)
	(wire
		(pts
			(xy 52.705 190.5) (xy 52.705 189.23)
		)
		(stroke
			(width 0)
			(type default)
		)
	)
	(wire
		(pts
			(xy 45.72 161.925) (xy 45.72 160.02)
		)
		(stroke
			(width 0)
			(type default)
		)
	)
	(wire
		(pts
			(xy 38.1 242.57) (xy 38.1 238.76)
		)
		(stroke
			(width 0)
			(type default)
		)
	)
	(polyline
		(pts
			(xy 36.83 154.305) (xy 43.815 154.305)
		)
		(stroke
			(width 0)
			(type dash)
		)
	)
	(wire
		(pts
			(xy 364.49 55.245) (xy 364.49 57.15)
		)
		(stroke
			(width 0)
			(type default)
		)
	)
	(wire
		(pts
			(xy 66.04 238.76) (xy 59.055 238.76)
		)
		(stroke
			(width 0)
			(type default)
		)
	)
	(wire
		(pts
			(xy 163.83 88.265) (xy 163.83 84.455)
		)
		(stroke
			(width 0)
			(type default)
		)
	)
	(wire
		(pts
			(xy 86.995 242.57) (xy 86.995 238.76)
		)
		(stroke
			(width 0)
			(type default)
		)
	)
	(polyline
		(pts
			(xy 327.66 126.365) (xy 327.66 117.475)
		)
		(stroke
			(width 0)
			(type dash)
		)
	)
	(wire
		(pts
			(xy 55.88 94.615) (xy 55.88 93.345)
		)
		(stroke
			(width 0)
			(type default)
		)
	)
	(wire
		(pts
			(xy 80.645 214.63) (xy 80.645 212.725)
		)
		(stroke
			(width 0)
			(type default)
		)
	)
	(wire
		(pts
			(xy 66.675 220.98) (xy 66.675 219.71)
		)
		(stroke
			(width 0)
			(type default)
		)
	)
	(wire
		(pts
			(xy 108.585 124.46) (xy 108.585 122.555)
		)
		(stroke
			(width 0)
			(type default)
		)
	)
	(wire
		(pts
			(xy 285.75 87.63) (xy 299.72 87.63)
		)
		(stroke
			(width 0)
			(type default)
		)
	)
	(wire
		(pts
			(xy 47.625 88.265) (xy 47.625 84.455)
		)
		(stroke
			(width 0)
			(type default)
		)
	)
	(wire
		(pts
			(xy 123.19 181.61) (xy 116.205 181.61)
		)
		(stroke
			(width 0)
			(type default)
		)
	)
	(wire
		(pts
			(xy 143.51 222.25) (xy 143.51 220.345)
		)
		(stroke
			(width 0)
			(type default)
		)
	)
	(polyline
		(pts
			(xy 36.195 113.03) (xy 37.465 113.03)
		)
		(stroke
			(width 0)
			(type dash)
		)
	)
	(wire
		(pts
			(xy 80.645 220.98) (xy 80.645 219.71)
		)
		(stroke
			(width 0)
			(type default)
		)
	)
	(wire
		(pts
			(xy 344.805 118.745) (xy 344.805 120.65)
		)
		(stroke
			(width 0)
			(type default)
		)
	)
	(wire
		(pts
			(xy 137.16 153.035) (xy 130.175 153.035)
		)
		(stroke
			(width 0)
			(type default)
		)
	)
	(wire
		(pts
			(xy 172.085 88.265) (xy 172.085 84.455)
		)
		(stroke
			(width 0)
			(type default)
		)
	)
	(wire
		(pts
			(xy 45.72 154.94) (xy 45.72 153.035)
		)
		(stroke
			(width 0)
			(type default)
		)
	)
	(wire
		(pts
			(xy 208.28 95.25) (xy 208.28 102.87)
		)
		(stroke
			(width 0)
			(type default)
		)
	)
	(wire
		(pts
			(xy 125.095 124.46) (xy 125.095 122.555)
		)
		(stroke
			(width 0)
			(type default)
		)
	)
	(wire
		(pts
			(xy 38.735 112.395) (xy 38.735 113.665)
		)
		(stroke
			(width 0)
			(type default)
		)
	)
	(wire
		(pts
			(xy 241.3 97.79) (xy 238.76 97.79)
		)
		(stroke
			(width 0)
			(type default)
		)
	)
	(polyline
		(pts
			(xy 113.03 213.995) (xy 113.03 220.98)
		)
		(stroke
			(width 0)
			(type dash)
		)
	)
	(wire
		(pts
			(xy 38.735 154.94) (xy 38.735 153.035)
		)
		(stroke
			(width 0)
			(type default)
		)
	)
	(wire
		(pts
			(xy 158.115 191.135) (xy 158.115 189.23)
		)
		(stroke
			(width 0)
			(type default)
		)
	)
	(wire
		(pts
			(xy 38.735 184.15) (xy 38.735 181.61)
		)
		(stroke
			(width 0)
			(type default)
		)
	)
	(wire
		(pts
			(xy 116.205 155.575) (xy 116.205 153.035)
		)
		(stroke
			(width 0)
			(type default)
		)
	)
	(polyline
		(pts
			(xy 85.725 67.945) (xy 85.725 58.42)
		)
		(stroke
			(width 0)
			(type dash)
		)
	)
	(wire
		(pts
			(xy 92.075 124.46) (xy 92.075 122.555)
		)
		(stroke
			(width 0)
			(type default)
		)
	)
	(wire
		(pts
			(xy 141.605 124.46) (xy 141.605 122.555)
		)
		(stroke
			(width 0)
			(type default)
		)
	)
	(wire
		(pts
			(xy 158.115 181.61) (xy 151.13 181.61)
		)
		(stroke
			(width 0)
			(type default)
		)
	)
	(wire
		(pts
			(xy 72.39 68.58) (xy 72.39 67.31)
		)
		(stroke
			(width 0)
			(type default)
		)
	)
	(wire
		(pts
			(xy 143.51 215.265) (xy 143.51 212.725)
		)
		(stroke
			(width 0)
			(type default)
		)
	)
	(wire
		(pts
			(xy 52.705 184.15) (xy 52.705 181.61)
		)
		(stroke
			(width 0)
			(type default)
		)
	)
	(wire
		(pts
			(xy 38.735 151.765) (xy 38.735 153.035)
		)
		(stroke
			(width 0)
			(type default)
		)
	)
	(wire
		(pts
			(xy 52.705 220.98) (xy 52.705 219.71)
		)
		(stroke
			(width 0)
			(type default)
		)
	)
	(wire
		(pts
			(xy 59.69 214.63) (xy 59.69 212.725)
		)
		(stroke
			(width 0)
			(type default)
		)
	)
	(wire
		(pts
			(xy 52.07 242.57) (xy 52.07 238.76)
		)
		(stroke
			(width 0)
			(type default)
		)
	)
	(polyline
		(pts
			(xy 353.695 53.975) (xy 353.695 62.865)
		)
		(stroke
			(width 0)
			(type dash)
		)
	)
	(wire
		(pts
			(xy 57.15 68.58) (xy 57.15 67.31)
		)
		(stroke
			(width 0)
			(type default)
		)
	)
	(wire
		(pts
			(xy 330.835 87.63) (xy 340.995 87.63)
		)
		(stroke
			(width 0)
			(type default)
		)
	)
	(wire
		(pts
			(xy 137.16 181.61) (xy 130.175 181.61)
		)
		(stroke
			(width 0)
			(type default)
		)
	)
	(wire
		(pts
			(xy 122.555 212.725) (xy 115.57 212.725)
		)
		(stroke
			(width 0)
			(type default)
		)
	)
	(wire
		(pts
			(xy 151.13 181.61) (xy 144.145 181.61)
		)
		(stroke
			(width 0)
			(type default)
		)
	)
	(symbol
		(lib_id "antmicropower:GND")
		(at 38.735 161.925 0)
		(unit 1)
		(exclude_from_sim no)
		(in_bom yes)
		(on_board yes)
		(dnp no)
		(fields_autoplaced yes)
		(property "Reference" "#PWR0122"
			(at 38.735 168.275 0)
			(effects
				(font
					(size 1.27 1.27)
				)
				(hide yes)
			)
		)
		(property "Value" "GND"
			(at 40.64 163.195 0)
			(effects
				(font
					(size 1.27 1.27)
					(thickness 0.15)
				)
				(justify left)
			)
		)
		(property "Footprint" ""
			(at 47.625 169.545 0)
			(effects
				(font
					(size 1.27 1.27)
					(thickness 0.15)
				)
				(justify left bottom)
				(hide yes)
			)
		)
		(property "Datasheet" ""
			(at 47.625 174.625 0)
			(effects
				(font
					(size 1.27 1.27)
					(thickness 0.15)
				)
				(justify left bottom)
				(hide yes)
			)
		)
		(property "Description" ""
			(at 47.625 177.165 0)
			(effects
				(font
					(size 1.27 1.27)
				)
				(justify left bottom)
				(hide yes)
			)
		)
		(property "Author" "Antmicro"
			(at 47.625 169.545 0)
			(effects
				(font
					(size 1.27 1.27)
					(thickness 0.15)
				)
				(justify left bottom)
				(hide yes)
			)
		)
		(property "License" "Apache-2.0"
			(at 47.625 172.085 0)
			(effects
				(font
					(size 1.27 1.27)
					(thickness 0.15)
				)
				(justify left bottom)
				(hide yes)
			)
		)
		(pin "1"
		)
		(instances
			(project "sodimm-ddr5-tester"
				(path ""
					(reference "#PWR0122")
					(unit 1)
				)
			)
		)
	)
	(symbol
		(lib_id "antmicropower:GND")
		(at 141.605 124.46 0)
		(unit 1)
		(exclude_from_sim no)
		(in_bom yes)
		(on_board yes)
		(dnp no)
		(fields_autoplaced yes)
		(property "Reference" "#PWR0133"
			(at 141.605 130.81 0)
			(effects
				(font
					(size 1.27 1.27)
				)
				(hide yes)
			)
		)
		(property "Value" "GND"
			(at 143.51 125.73 0)
			(effects
				(font
					(size 1.27 1.27)
					(thickness 0.15)
				)
				(justify left)
			)
		)
		(property "Footprint" ""
			(at 150.495 132.08 0)
			(effects
				(font
					(size 1.27 1.27)
					(thickness 0.15)
				)
				(justify left bottom)
				(hide yes)
			)
		)
		(property "Datasheet" ""
			(at 150.495 137.16 0)
			(effects
				(font
					(size 1.27 1.27)
					(thickness 0.15)
				)
				(justify left bottom)
				(hide yes)
			)
		)
		(property "Description" ""
			(at 150.495 139.7 0)
			(effects
				(font
					(size 1.27 1.27)
				)
				(justify left bottom)
				(hide yes)
			)
		)
		(property "Author" "Antmicro"
			(at 150.495 132.08 0)
			(effects
				(font
					(size 1.27 1.27)
					(thickness 0.15)
				)
				(justify left bottom)
				(hide yes)
			)
		)
		(property "License" "Apache-2.0"
			(at 150.495 134.62 0)
			(effects
				(font
					(size 1.27 1.27)
					(thickness 0.15)
				)
				(justify left bottom)
				(hide yes)
			)
		)
		(pin "1"
		)
		(instances
			(project "sodimm-ddr5-tester"
				(path ""
					(reference "#PWR0133")
					(unit 1)
				)
			)
		)
	)
	(symbol
		(lib_id "antmicropower:GND")
		(at 72.39 94.615 0)
		(unit 1)
		(exclude_from_sim no)
		(in_bom yes)
		(on_board yes)
		(dnp no)
		(fields_autoplaced yes)
		(property "Reference" "#PWR089"
			(at 72.39 100.965 0)
			(effects
				(font
					(size 1.27 1.27)
				)
				(hide yes)
			)
		)
		(property "Value" "GND"
			(at 74.93 95.885 0)
			(effects
				(font
					(size 1.27 1.27)
					(thickness 0.15)
				)
				(justify left)
			)
		)
		(property "Footprint" ""
			(at 81.28 102.235 0)
			(effects
				(font
					(size 1.27 1.27)
					(thickness 0.15)
				)
				(justify left bottom)
				(hide yes)
			)
		)
		(property "Datasheet" ""
			(at 81.28 107.315 0)
			(effects
				(font
					(size 1.27 1.27)
					(thickness 0.15)
				)
				(justify left bottom)
				(hide yes)
			)
		)
		(property "Description" ""
			(at 81.28 109.855 0)
			(effects
				(font
					(size 1.27 1.27)
				)
				(justify left bottom)
				(hide yes)
			)
		)
		(property "Author" "Antmicro"
			(at 81.28 102.235 0)
			(effects
				(font
					(size 1.27 1.27)
					(thickness 0.15)
				)
				(justify left bottom)
				(hide yes)
			)
		)
		(property "License" "Apache-2.0"
			(at 81.28 104.775 0)
			(effects
				(font
					(size 1.27 1.27)
					(thickness 0.15)
				)
				(justify left bottom)
				(hide yes)
			)
		)
		(pin "1"
		)
		(instances
			(project "sodimm-ddr5-tester"
				(path ""
					(reference "#PWR089")
					(unit 1)
				)
			)
		)
	)
	(symbol
		(lib_id "antmicropower:GND")
		(at 122.555 94.615 0)
		(unit 1)
		(exclude_from_sim no)
		(in_bom yes)
		(on_board yes)
		(dnp no)
		(fields_autoplaced yes)
		(property "Reference" "#PWR0124"
			(at 122.555 100.965 0)
			(effects
				(font
					(size 1.27 1.27)
				)
				(hide yes)
			)
		)
		(property "Value" "GND"
			(at 124.46 95.885 0)
			(effects
				(font
					(size 1.27 1.27)
					(thickness 0.15)
				)
				(justify left)
			)
		)
		(property "Footprint" ""
			(at 131.445 102.235 0)
			(effects
				(font
					(size 1.27 1.27)
					(thickness 0.15)
				)
				(justify left bottom)
				(hide yes)
			)
		)
		(property "Datasheet" ""
			(at 131.445 107.315 0)
			(effects
				(font
					(size 1.27 1.27)
					(thickness 0.15)
				)
				(justify left bottom)
				(hide yes)
			)
		)
		(property "Description" ""
			(at 131.445 109.855 0)
			(effects
				(font
					(size 1.27 1.27)
				)
				(justify left bottom)
				(hide yes)
			)
		)
		(property "Author" "Antmicro"
			(at 131.445 102.235 0)
			(effects
				(font
					(size 1.27 1.27)
					(thickness 0.15)
				)
				(justify left bottom)
				(hide yes)
			)
		)
		(property "License" "Apache-2.0"
			(at 131.445 104.775 0)
			(effects
				(font
					(size 1.27 1.27)
					(thickness 0.15)
				)
				(justify left bottom)
				(hide yes)
			)
		)
		(pin "1"
		)
		(instances
			(project "sodimm-ddr5-tester"
				(path ""
					(reference "#PWR0124")
					(unit 1)
				)
			)
		)
	)
	(symbol
		(lib_id "antmicroCapacitors0402:C_100n_0402")
		(at 130.175 189.23 90)
		(unit 1)
		(exclude_from_sim no)
		(in_bom yes)
		(on_board yes)
		(dnp no)
		(property "Reference" "C66"
			(at 130.81 184.785 90)
			(effects
				(font
					(size 1.27 1.27)
					(thickness 0.15)
				)
				(justify right)
			)
		)
		(property "Value" "C_100n_0402"
			(at 140.335 168.91 0)
			(effects
				(font
					(size 1.27 1.27)
					(thickness 0.15)
				)
				(justify left bottom)
				(hide yes)
			)
		)
		(property "Footprint" "antmicro-footprints:C_0402_1005Metric"
			(at 142.875 168.91 0)
			(effects
				(font
					(size 1.27 1.27)
					(thickness 0.15)
				)
				(justify left bottom)
				(hide yes)
			)
		)
		(property "Datasheet" "https://www.murata.com/products/productdetail?partno=GRM155R61H104KE14%23"
			(at 145.415 168.91 0)
			(effects
				(font
					(size 1.27 1.27)
					(thickness 0.15)
				)
				(justify left bottom)
				(hide yes)
			)
		)
		(property "Description" ""
			(at 130.175 189.23 0)
			(effects
				(font
					(size 1.27 1.27)
				)
			)
		)
		(property "MPN" "GRM155R61H104KE14D"
			(at 147.955 168.91 0)
			(effects
				(font
					(size 1.27 1.27)
					(thickness 0.15)
				)
				(justify left bottom)
				(hide yes)
			)
		)
		(property "Manufacturer" "Murata"
			(at 150.495 168.91 0)
			(effects
				(font
					(size 1.27 1.27)
					(thickness 0.15)
				)
				(justify left bottom)
				(hide yes)
			)
		)
		(property "License" "Apache-2.0"
			(at 153.035 168.91 0)
			(effects
				(font
					(size 1.27 1.27)
					(thickness 0.15)
				)
				(justify left bottom)
				(hide yes)
			)
		)
		(property "Author" "Antmicro"
			(at 155.575 168.91 0)
			(effects
				(font
					(size 1.27 1.27)
					(thickness 0.15)
				)
				(justify left bottom)
				(hide yes)
			)
		)
		(property "Val" "100n"
			(at 130.81 188.595 90)
			(effects
				(font
					(size 1.27 1.27)
					(thickness 0.15)
				)
				(justify right)
			)
		)
		(property "Voltage" "50V"
			(at 158.115 168.91 0)
			(effects
				(font
					(size 1.27 1.27)
				)
				(justify left bottom)
				(hide yes)
			)
		)
		(property "Dielectric" "X5R"
			(at 160.655 168.91 0)
			(effects
				(font
					(size 1.27 1.27)
				)
				(justify left bottom)
				(hide yes)
			)
		)
		(pin "1"
		)
		(pin "2"
		)
		(instances
			(project "sodimm-ddr5-tester"
				(path ""
					(reference "C66")
					(unit 1)
				)
			)
		)
	)
	(symbol
		(lib_id "antmicroCapacitors0402:C_100n_0402")
		(at 339.725 62.23 90)
		(unit 1)
		(exclude_from_sim no)
		(in_bom yes)
		(on_board yes)
		(dnp no)
		(property "Reference" "C98"
			(at 340.36 57.785 90)
			(effects
				(font
					(size 1.27 1.27)
					(thickness 0.15)
				)
				(justify right)
			)
		)
		(property "Value" "C_100n_0402"
			(at 349.885 41.91 0)
			(effects
				(font
					(size 1.27 1.27)
					(thickness 0.15)
				)
				(justify left bottom)
				(hide yes)
			)
		)
		(property "Footprint" "antmicro-footprints:C_0402_1005Metric"
			(at 352.425 41.91 0)
			(effects
				(font
					(size 1.27 1.27)
					(thickness 0.15)
				)
				(justify left bottom)
				(hide yes)
			)
		)
		(property "Datasheet" "https://www.murata.com/products/productdetail?partno=GRM155R61H104KE14%23"
			(at 354.965 41.91 0)
			(effects
				(font
					(size 1.27 1.27)
					(thickness 0.15)
				)
				(justify left bottom)
				(hide yes)
			)
		)
		(property "Description" ""
			(at 339.725 62.23 0)
			(effects
				(font
					(size 1.27 1.27)
				)
			)
		)
		(property "MPN" "GRM155R61H104KE14D"
			(at 357.505 41.91 0)
			(effects
				(font
					(size 1.27 1.27)
					(thickness 0.15)
				)
				(justify left bottom)
				(hide yes)
			)
		)
		(property "Manufacturer" "Murata"
			(at 360.045 41.91 0)
			(effects
				(font
					(size 1.27 1.27)
					(thickness 0.15)
				)
				(justify left bottom)
				(hide yes)
			)
		)
		(property "License" "Apache-2.0"
			(at 362.585 41.91 0)
			(effects
				(font
					(size 1.27 1.27)
					(thickness 0.15)
				)
				(justify left bottom)
				(hide yes)
			)
		)
		(property "Author" "Antmicro"
			(at 365.125 41.91 0)
			(effects
				(font
					(size 1.27 1.27)
					(thickness 0.15)
				)
				(justify left bottom)
				(hide yes)
			)
		)
		(property "Val" "100n"
			(at 340.36 61.595 90)
			(effects
				(font
					(size 1.27 1.27)
					(thickness 0.15)
				)
				(justify right)
			)
		)
		(property "Voltage" "50V"
			(at 367.665 41.91 0)
			(effects
				(font
					(size 1.27 1.27)
				)
				(justify left bottom)
				(hide yes)
			)
		)
		(property "Dielectric" "X5R"
			(at 370.205 41.91 0)
			(effects
				(font
					(size 1.27 1.27)
				)
				(justify left bottom)
				(hide yes)
			)
		)
		(pin "1"
		)
		(pin "2"
		)
		(instances
			(project "sodimm-ddr5-tester"
				(path ""
					(reference "C98")
					(unit 1)
				)
			)
		)
	)
	(symbol
		(lib_id "antmicropower:+3V3")
		(at 38.735 151.765 0)
		(unit 1)
		(exclude_from_sim no)
		(in_bom yes)
		(on_board yes)
		(dnp no)
		(property "Reference" "#PWR0121"
			(at 38.735 155.575 0)
			(effects
				(font
					(size 1.27 1.27)
				)
				(hide yes)
			)
		)
		(property "Value" "+3V3"
			(at 35.56 149.225 0)
			(effects
				(font
					(size 1.27 1.27)
					(thickness 0.15)
				)
				(justify left bottom)
			)
		)
		(property "Footprint" ""
			(at 53.975 159.385 0)
			(effects
				(font
					(size 1.27 1.27)
					(thickness 0.15)
				)
				(justify left bottom)
				(hide yes)
			)
		)
		(property "Datasheet" ""
			(at 53.975 161.925 0)
			(effects
				(font
					(size 1.27 1.27)
					(thickness 0.15)
				)
				(justify left bottom)
				(hide yes)
			)
		)
		(property "Description" ""
			(at 38.735 151.765 0)
			(effects
				(font
					(size 1.27 1.27)
				)
			)
		)
		(property "Author" "Antmicro"
			(at 53.975 154.305 0)
			(effects
				(font
					(size 1.27 1.27)
					(thickness 0.15)
				)
				(justify left bottom)
				(hide yes)
			)
		)
		(property "License" "Apache-2.0"
			(at 53.975 156.845 0)
			(effects
				(font
					(size 1.27 1.27)
					(thickness 0.15)
				)
				(justify left bottom)
				(hide yes)
			)
		)
		(pin "1"
		)
		(instances
			(project "sodimm-ddr5-tester"
				(path ""
					(reference "#PWR0121")
					(unit 1)
				)
			)
		)
	)
	(symbol
		(lib_id "antmicropower:GND")
		(at 73.66 220.98 0)
		(unit 1)
		(exclude_from_sim no)
		(in_bom yes)
		(on_board yes)
		(dnp no)
		(fields_autoplaced yes)
		(property "Reference" "#PWR094"
			(at 73.66 227.33 0)
			(effects
				(font
					(size 1.27 1.27)
				)
				(hide yes)
			)
		)
		(property "Value" "GND"
			(at 76.2 222.25 0)
			(effects
				(font
					(size 1.27 1.27)
					(thickness 0.15)
				)
				(justify left)
			)
		)
		(property "Footprint" ""
			(at 82.55 228.6 0)
			(effects
				(font
					(size 1.27 1.27)
					(thickness 0.15)
				)
				(justify left bottom)
				(hide yes)
			)
		)
		(property "Datasheet" ""
			(at 82.55 233.68 0)
			(effects
				(font
					(size 1.27 1.27)
					(thickness 0.15)
				)
				(justify left bottom)
				(hide yes)
			)
		)
		(property "Description" ""
			(at 82.55 236.22 0)
			(effects
				(font
					(size 1.27 1.27)
				)
				(justify left bottom)
				(hide yes)
			)
		)
		(property "Author" "Antmicro"
			(at 82.55 228.6 0)
			(effects
				(font
					(size 1.27 1.27)
					(thickness 0.15)
				)
				(justify left bottom)
				(hide yes)
			)
		)
		(property "License" "Apache-2.0"
			(at 82.55 231.14 0)
			(effects
				(font
					(size 1.27 1.27)
					(thickness 0.15)
				)
				(justify left bottom)
				(hide yes)
			)
		)
		(pin "1"
		)
		(instances
			(project "sodimm-ddr5-tester"
				(path ""
					(reference "#PWR094")
					(unit 1)
				)
			)
		)
	)
	(symbol
		(lib_id "antmicropower:+1V8")
		(at 299.72 81.915 0)
		(unit 1)
		(exclude_from_sim no)
		(in_bom yes)
		(on_board yes)
		(dnp no)
		(fields_autoplaced yes)
		(property "Reference" "#PWR0162"
			(at 299.72 85.725 0)
			(effects
				(font
					(size 1.27 1.27)
				)
				(hide yes)
			)
		)
		(property "Value" "+1V8"
			(at 296.545 79.375 0)
			(effects
				(font
					(size 1.27 1.27)
					(thickness 0.15)
				)
				(justify left bottom)
			)
		)
		(property "Footprint" ""
			(at 314.96 89.535 0)
			(effects
				(font
					(size 1.27 1.27)
					(thickness 0.15)
				)
				(justify left bottom)
				(hide yes)
			)
		)
		(property "Datasheet" ""
			(at 314.96 92.075 0)
			(effects
				(font
					(size 1.27 1.27)
					(thickness 0.15)
				)
				(justify left bottom)
				(hide yes)
			)
		)
		(property "Description" ""
			(at 299.72 81.915 0)
			(effects
				(font
					(size 1.27 1.27)
				)
			)
		)
		(property "Author" "Antmicro"
			(at 314.96 86.995 0)
			(effects
				(font
					(size 1.27 1.27)
					(thickness 0.15)
				)
				(justify left bottom)
				(hide yes)
			)
		)
		(property "License" "Apache-2.0"
			(at 314.96 89.535 0)
			(effects
				(font
					(size 1.27 1.27)
					(thickness 0.15)
				)
				(justify left bottom)
				(hide yes)
			)
		)
		(pin "1"
		)
		(instances
			(project "sodimm-ddr5-tester"
				(path ""
					(reference "#PWR0162")
					(unit 1)
				)
			)
		)
	)
	(symbol
		(lib_id "antmicropower:GND")
		(at 158.115 191.135 0)
		(unit 1)
		(exclude_from_sim no)
		(in_bom yes)
		(on_board yes)
		(dnp no)
		(fields_autoplaced yes)
		(property "Reference" "#PWR0131"
			(at 158.115 197.485 0)
			(effects
				(font
					(size 1.27 1.27)
				)
				(hide yes)
			)
		)
		(property "Value" "GND"
			(at 160.02 192.405 0)
			(effects
				(font
					(size 1.27 1.27)
					(thickness 0.15)
				)
				(justify left)
			)
		)
		(property "Footprint" ""
			(at 167.005 198.755 0)
			(effects
				(font
					(size 1.27 1.27)
					(thickness 0.15)
				)
				(justify left bottom)
				(hide yes)
			)
		)
		(property "Datasheet" ""
			(at 167.005 203.835 0)
			(effects
				(font
					(size 1.27 1.27)
					(thickness 0.15)
				)
				(justify left bottom)
				(hide yes)
			)
		)
		(property "Description" ""
			(at 167.005 206.375 0)
			(effects
				(font
					(size 1.27 1.27)
				)
				(justify left bottom)
				(hide yes)
			)
		)
		(property "Author" "Antmicro"
			(at 167.005 198.755 0)
			(effects
				(font
					(size 1.27 1.27)
					(thickness 0.15)
				)
				(justify left bottom)
				(hide yes)
			)
		)
		(property "License" "Apache-2.0"
			(at 167.005 201.295 0)
			(effects
				(font
					(size 1.27 1.27)
					(thickness 0.15)
				)
				(justify left bottom)
				(hide yes)
			)
		)
		(pin "1"
		)
		(instances
			(project "sodimm-ddr5-tester"
				(path ""
					(reference "#PWR0131")
					(unit 1)
				)
			)
		)
	)
	(symbol
		(lib_id "antmicroCapacitors0402:C_100n_0402")
		(at 158.115 189.23 90)
		(unit 1)
		(exclude_from_sim no)
		(in_bom yes)
		(on_board yes)
		(dnp no)
		(property "Reference" "C82"
			(at 158.75 184.785 90)
			(effects
				(font
					(size 1.27 1.27)
					(thickness 0.15)
				)
				(justify right)
			)
		)
		(property "Value" "C_100n_0402"
			(at 168.275 168.91 0)
			(effects
				(font
					(size 1.27 1.27)
					(thickness 0.15)
				)
				(justify left bottom)
				(hide yes)
			)
		)
		(property "Footprint" "antmicro-footprints:C_0402_1005Metric"
			(at 170.815 168.91 0)
			(effects
				(font
					(size 1.27 1.27)
					(thickness 0.15)
				)
				(justify left bottom)
				(hide yes)
			)
		)
		(property "Datasheet" "https://www.murata.com/products/productdetail?partno=GRM155R61H104KE14%23"
			(at 173.355 168.91 0)
			(effects
				(font
					(size 1.27 1.27)
					(thickness 0.15)
				)
				(justify left bottom)
				(hide yes)
			)
		)
		(property "Description" ""
			(at 158.115 189.23 0)
			(effects
				(font
					(size 1.27 1.27)
				)
			)
		)
		(property "MPN" "GRM155R61H104KE14D"
			(at 175.895 168.91 0)
			(effects
				(font
					(size 1.27 1.27)
					(thickness 0.15)
				)
				(justify left bottom)
				(hide yes)
			)
		)
		(property "Manufacturer" "Murata"
			(at 178.435 168.91 0)
			(effects
				(font
					(size 1.27 1.27)
					(thickness 0.15)
				)
				(justify left bottom)
				(hide yes)
			)
		)
		(property "License" "Apache-2.0"
			(at 180.975 168.91 0)
			(effects
				(font
					(size 1.27 1.27)
					(thickness 0.15)
				)
				(justify left bottom)
				(hide yes)
			)
		)
		(property "Author" "Antmicro"
			(at 183.515 168.91 0)
			(effects
				(font
					(size 1.27 1.27)
					(thickness 0.15)
				)
				(justify left bottom)
				(hide yes)
			)
		)
		(property "Val" "100n"
			(at 158.75 188.595 90)
			(effects
				(font
					(size 1.27 1.27)
					(thickness 0.15)
				)
				(justify right)
			)
		)
		(property "Voltage" "50V"
			(at 186.055 168.91 0)
			(effects
				(font
					(size 1.27 1.27)
				)
				(justify left bottom)
				(hide yes)
			)
		)
		(property "Dielectric" "X5R"
			(at 188.595 168.91 0)
			(effects
				(font
					(size 1.27 1.27)
				)
				(justify left bottom)
				(hide yes)
			)
		)
		(pin "1"
		)
		(pin "2"
		)
		(instances
			(project "sodimm-ddr5-tester"
				(path ""
					(reference "C82")
					(unit 1)
				)
			)
		)
	)
	(symbol
		(lib_id "antmicropower:GND")
		(at 172.085 94.615 0)
		(unit 1)
		(exclude_from_sim no)
		(in_bom yes)
		(on_board yes)
		(dnp no)
		(fields_autoplaced yes)
		(property "Reference" "#PWR0142"
			(at 172.085 100.965 0)
			(effects
				(font
					(size 1.27 1.27)
				)
				(hide yes)
			)
		)
		(property "Value" "GND"
			(at 173.99 95.885 0)
			(effects
				(font
					(size 1.27 1.27)
					(thickness 0.15)
				)
				(justify left)
			)
		)
		(property "Footprint" ""
			(at 180.975 102.235 0)
			(effects
				(font
					(size 1.27 1.27)
					(thickness 0.15)
				)
				(justify left bottom)
				(hide yes)
			)
		)
		(property "Datasheet" ""
			(at 180.975 107.315 0)
			(effects
				(font
					(size 1.27 1.27)
					(thickness 0.15)
				)
				(justify left bottom)
				(hide yes)
			)
		)
		(property "Description" ""
			(at 180.975 109.855 0)
			(effects
				(font
					(size 1.27 1.27)
				)
				(justify left bottom)
				(hide yes)
			)
		)
		(property "Author" "Antmicro"
			(at 180.975 102.235 0)
			(effects
				(font
					(size 1.27 1.27)
					(thickness 0.15)
				)
				(justify left bottom)
				(hide yes)
			)
		)
		(property "License" "Apache-2.0"
			(at 180.975 104.775 0)
			(effects
				(font
					(size 1.27 1.27)
					(thickness 0.15)
				)
				(justify left bottom)
				(hide yes)
			)
		)
		(pin "1"
		)
		(instances
			(project "sodimm-ddr5-tester"
				(path ""
					(reference "#PWR0142")
					(unit 1)
				)
			)
		)
	)
	(symbol
		(lib_id "antmicropower:GND")
		(at 143.51 222.25 0)
		(unit 1)
		(exclude_from_sim no)
		(in_bom yes)
		(on_board yes)
		(dnp no)
		(fields_autoplaced yes)
		(property "Reference" "#PWR0143"
			(at 143.51 228.6 0)
			(effects
				(font
					(size 1.27 1.27)
				)
				(hide yes)
			)
		)
		(property "Value" "GND"
			(at 146.05 223.52 0)
			(effects
				(font
					(size 1.27 1.27)
					(thickness 0.15)
				)
				(justify left)
			)
		)
		(property "Footprint" ""
			(at 152.4 229.87 0)
			(effects
				(font
					(size 1.27 1.27)
					(thickness 0.15)
				)
				(justify left bottom)
				(hide yes)
			)
		)
		(property "Datasheet" ""
			(at 152.4 234.95 0)
			(effects
				(font
					(size 1.27 1.27)
					(thickness 0.15)
				)
				(justify left bottom)
				(hide yes)
			)
		)
		(property "Description" ""
			(at 152.4 237.49 0)
			(effects
				(font
					(size 1.27 1.27)
				)
				(justify left bottom)
				(hide yes)
			)
		)
		(property "Author" "Antmicro"
			(at 152.4 229.87 0)
			(effects
				(font
					(size 1.27 1.27)
					(thickness 0.15)
				)
				(justify left bottom)
				(hide yes)
			)
		)
		(property "License" "Apache-2.0"
			(at 152.4 232.41 0)
			(effects
				(font
					(size 1.27 1.27)
					(thickness 0.15)
				)
				(justify left bottom)
				(hide yes)
			)
		)
		(pin "1"
		)
		(instances
			(project "sodimm-ddr5-tester"
				(path ""
					(reference "#PWR0143")
					(unit 1)
				)
			)
		)
	)
	(symbol
		(lib_id "antmicropower:+1V0")
		(at 239.395 80.01 0)
		(unit 1)
		(exclude_from_sim no)
		(in_bom yes)
		(on_board yes)
		(dnp no)
		(fields_autoplaced yes)
		(property "Reference" "#PWR0154"
			(at 239.395 83.82 0)
			(effects
				(font
					(size 1.27 1.27)
				)
				(hide yes)
			)
		)
		(property "Value" "+1V0"
			(at 239.395 76.454 0)
			(effects
				(font
					(size 1.27 1.27)
				)
			)
		)
		(property "Footprint" ""
			(at 239.395 80.01 0)
			(effects
				(font
					(size 1.27 1.27)
				)
				(hide yes)
			)
		)
		(property "Datasheet" ""
			(at 239.395 80.01 0)
			(effects
				(font
					(size 1.27 1.27)
				)
				(hide yes)
			)
		)
		(property "Description" ""
			(at 239.395 80.01 0)
			(effects
				(font
					(size 1.27 1.27)
				)
			)
		)
		(pin "1"
		)
		(instances
			(project "sodimm-ddr5-tester"
				(path ""
					(reference "#PWR0154")
					(unit 1)
				)
			)
		)
	)
	(symbol
		(lib_id "antmicropower:GND")
		(at 45.085 248.92 0)
		(unit 1)
		(exclude_from_sim no)
		(in_bom yes)
		(on_board yes)
		(dnp no)
		(fields_autoplaced yes)
		(property "Reference" "#PWR068"
			(at 45.085 255.27 0)
			(effects
				(font
					(size 1.27 1.27)
				)
				(hide yes)
			)
		)
		(property "Value" "GND"
			(at 46.99 250.19 0)
			(effects
				(font
					(size 1.27 1.27)
					(thickness 0.15)
				)
				(justify left)
			)
		)
		(property "Footprint" ""
			(at 53.975 256.54 0)
			(effects
				(font
					(size 1.27 1.27)
					(thickness 0.15)
				)
				(justify left bottom)
				(hide yes)
			)
		)
		(property "Datasheet" ""
			(at 53.975 261.62 0)
			(effects
				(font
					(size 1.27 1.27)
					(thickness 0.15)
				)
				(justify left bottom)
				(hide yes)
			)
		)
		(property "Description" ""
			(at 53.975 264.16 0)
			(effects
				(font
					(size 1.27 1.27)
				)
				(justify left bottom)
				(hide yes)
			)
		)
		(property "Author" "Antmicro"
			(at 53.975 256.54 0)
			(effects
				(font
					(size 1.27 1.27)
					(thickness 0.15)
				)
				(justify left bottom)
				(hide yes)
			)
		)
		(property "License" "Apache-2.0"
			(at 53.975 259.08 0)
			(effects
				(font
					(size 1.27 1.27)
					(thickness 0.15)
				)
				(justify left bottom)
				(hide yes)
			)
		)
		(pin "1"
		)
		(instances
			(project "sodimm-ddr5-tester"
				(path ""
					(reference "#PWR068")
					(unit 1)
				)
			)
		)
	)
	(symbol
		(lib_id "antmicroCapacitors0402:C_100n_0402")
		(at 150.495 220.345 90)
		(unit 1)
		(exclude_from_sim no)
		(in_bom yes)
		(on_board yes)
		(dnp no)
		(property "Reference" "C94"
			(at 151.13 215.9 90)
			(effects
				(font
					(size 1.27 1.27)
					(thickness 0.15)
				)
				(justify right)
			)
		)
		(property "Value" "C_100n_0402"
			(at 160.655 200.025 0)
			(effects
				(font
					(size 1.27 1.27)
					(thickness 0.15)
				)
				(justify left bottom)
				(hide yes)
			)
		)
		(property "Footprint" "antmicro-footprints:C_0402_1005Metric"
			(at 163.195 200.025 0)
			(effects
				(font
					(size 1.27 1.27)
					(thickness 0.15)
				)
				(justify left bottom)
				(hide yes)
			)
		)
		(property "Datasheet" "https://www.murata.com/products/productdetail?partno=GRM155R61H104KE14%23"
			(at 165.735 200.025 0)
			(effects
				(font
					(size 1.27 1.27)
					(thickness 0.15)
				)
				(justify left bottom)
				(hide yes)
			)
		)
		(property "Description" ""
			(at 150.495 220.345 0)
			(effects
				(font
					(size 1.27 1.27)
				)
			)
		)
		(property "MPN" "GRM155R61H104KE14D"
			(at 168.275 200.025 0)
			(effects
				(font
					(size 1.27 1.27)
					(thickness 0.15)
				)
				(justify left bottom)
				(hide yes)
			)
		)
		(property "Manufacturer" "Murata"
			(at 170.815 200.025 0)
			(effects
				(font
					(size 1.27 1.27)
					(thickness 0.15)
				)
				(justify left bottom)
				(hide yes)
			)
		)
		(property "License" "Apache-2.0"
			(at 173.355 200.025 0)
			(effects
				(font
					(size 1.27 1.27)
					(thickness 0.15)
				)
				(justify left bottom)
				(hide yes)
			)
		)
		(property "Author" "Antmicro"
			(at 175.895 200.025 0)
			(effects
				(font
					(size 1.27 1.27)
					(thickness 0.15)
				)
				(justify left bottom)
				(hide yes)
			)
		)
		(property "Val" "100n"
			(at 151.13 219.71 90)
			(effects
				(font
					(size 1.27 1.27)
					(thickness 0.15)
				)
				(justify right)
			)
		)
		(property "Voltage" "50V"
			(at 178.435 200.025 0)
			(effects
				(font
					(size 1.27 1.27)
				)
				(justify left bottom)
				(hide yes)
			)
		)
		(property "Dielectric" "X5R"
			(at 180.975 200.025 0)
			(effects
				(font
					(size 1.27 1.27)
				)
				(justify left bottom)
				(hide yes)
			)
		)
		(pin "1"
		)
		(pin "2"
		)
		(instances
			(project "sodimm-ddr5-tester"
				(path ""
					(reference "C94")
					(unit 1)
				)
			)
		)
	)
	(symbol
		(lib_id "antmicropower:GND")
		(at 359.41 127 0)
		(unit 1)
		(exclude_from_sim no)
		(in_bom yes)
		(on_board yes)
		(dnp no)
		(fields_autoplaced yes)
		(property "Reference" "#PWR0167"
			(at 359.41 133.35 0)
			(effects
				(font
					(size 1.27 1.27)
				)
				(hide yes)
			)
		)
		(property "Value" "GND"
			(at 361.95 128.27 0)
			(effects
				(font
					(size 1.27 1.27)
					(thickness 0.15)
				)
				(justify left)
			)
		)
		(property "Footprint" ""
			(at 368.3 134.62 0)
			(effects
				(font
					(size 1.27 1.27)
					(thickness 0.15)
				)
				(justify left bottom)
				(hide yes)
			)
		)
		(property "Datasheet" ""
			(at 368.3 139.7 0)
			(effects
				(font
					(size 1.27 1.27)
					(thickness 0.15)
				)
				(justify left bottom)
				(hide yes)
			)
		)
		(property "Description" ""
			(at 368.3 142.24 0)
			(effects
				(font
					(size 1.27 1.27)
				)
				(justify left bottom)
				(hide yes)
			)
		)
		(property "Author" "Antmicro"
			(at 368.3 134.62 0)
			(effects
				(font
					(size 1.27 1.27)
					(thickness 0.15)
				)
				(justify left bottom)
				(hide yes)
			)
		)
		(property "License" "Apache-2.0"
			(at 368.3 137.16 0)
			(effects
				(font
					(size 1.27 1.27)
					(thickness 0.15)
				)
				(justify left bottom)
				(hide yes)
			)
		)
		(pin "1"
		)
		(instances
			(project "sodimm-ddr5-tester"
				(path ""
					(reference "#PWR0167")
					(unit 1)
				)
			)
		)
	)
	(symbol
		(lib_id "antmicroCapacitors0402:C_100n_0402")
		(at 106.045 93.345 90)
		(unit 1)
		(exclude_from_sim no)
		(in_bom yes)
		(on_board yes)
		(dnp no)
		(property "Reference" "C65"
			(at 106.68 88.9 90)
			(effects
				(font
					(size 1.27 1.27)
					(thickness 0.15)
				)
				(justify right)
			)
		)
		(property "Value" "C_100n_0402"
			(at 116.205 73.025 0)
			(effects
				(font
					(size 1.27 1.27)
					(thickness 0.15)
				)
				(justify left bottom)
				(hide yes)
			)
		)
		(property "Footprint" "antmicro-footprints:C_0402_1005Metric"
			(at 118.745 73.025 0)
			(effects
				(font
					(size 1.27 1.27)
					(thickness 0.15)
				)
				(justify left bottom)
				(hide yes)
			)
		)
		(property "Datasheet" "https://www.murata.com/products/productdetail?partno=GRM155R61H104KE14%23"
			(at 121.285 73.025 0)
			(effects
				(font
					(size 1.27 1.27)
					(thickness 0.15)
				)
				(justify left bottom)
				(hide yes)
			)
		)
		(property "Description" ""
			(at 106.045 93.345 0)
			(effects
				(font
					(size 1.27 1.27)
				)
			)
		)
		(property "MPN" "GRM155R61H104KE14D"
			(at 123.825 73.025 0)
			(effects
				(font
					(size 1.27 1.27)
					(thickness 0.15)
				)
				(justify left bottom)
				(hide yes)
			)
		)
		(property "Manufacturer" "Murata"
			(at 126.365 73.025 0)
			(effects
				(font
					(size 1.27 1.27)
					(thickness 0.15)
				)
				(justify left bottom)
				(hide yes)
			)
		)
		(property "License" "Apache-2.0"
			(at 128.905 73.025 0)
			(effects
				(font
					(size 1.27 1.27)
					(thickness 0.15)
				)
				(justify left bottom)
				(hide yes)
			)
		)
		(property "Author" "Antmicro"
			(at 131.445 73.025 0)
			(effects
				(font
					(size 1.27 1.27)
					(thickness 0.15)
				)
				(justify left bottom)
				(hide yes)
			)
		)
		(property "Val" "100n"
			(at 106.68 92.71 90)
			(effects
				(font
					(size 1.27 1.27)
					(thickness 0.15)
				)
				(justify right)
			)
		)
		(property "Voltage" "50V"
			(at 133.985 73.025 0)
			(effects
				(font
					(size 1.27 1.27)
				)
				(justify left bottom)
				(hide yes)
			)
		)
		(property "Dielectric" "X5R"
			(at 136.525 73.025 0)
			(effects
				(font
					(size 1.27 1.27)
				)
				(justify left bottom)
				(hide yes)
			)
		)
		(pin "1"
		)
		(pin "2"
		)
		(instances
			(project "sodimm-ddr5-tester"
				(path ""
					(reference "C65")
					(unit 1)
				)
			)
		)
	)
	(symbol
		(lib_id "antmicroCapacitors0402:C_100n_0402")
		(at 53.975 160.02 90)
		(unit 1)
		(exclude_from_sim no)
		(in_bom yes)
		(on_board yes)
		(dnp no)
		(property "Reference" "C80"
			(at 58.42 155.575 90)
			(effects
				(font
					(size 1.27 1.27)
					(thickness 0.15)
				)
				(justify left)
			)
		)
		(property "Value" "C_100n_0402"
			(at 64.135 139.7 0)
			(effects
				(font
					(size 1.27 1.27)
					(thickness 0.15)
				)
				(justify left bottom)
				(hide yes)
			)
		)
		(property "Footprint" "antmicro-footprints:C_0402_1005Metric"
			(at 66.675 139.7 0)
			(effects
				(font
					(size 1.27 1.27)
					(thickness 0.15)
				)
				(justify left bottom)
				(hide yes)
			)
		)
		(property "Datasheet" "https://www.murata.com/products/productdetail?partno=GRM155R61H104KE14%23"
			(at 69.215 139.7 0)
			(effects
				(font
					(size 1.27 1.27)
					(thickness 0.15)
				)
				(justify left bottom)
				(hide yes)
			)
		)
		(property "Description" ""
			(at 53.975 160.02 0)
			(effects
				(font
					(size 1.27 1.27)
				)
			)
		)
		(property "MPN" "GRM155R61H104KE14D"
			(at 71.755 139.7 0)
			(effects
				(font
					(size 1.27 1.27)
					(thickness 0.15)
				)
				(justify left bottom)
				(hide yes)
			)
		)
		(property "Manufacturer" "Murata"
			(at 74.295 139.7 0)
			(effects
				(font
					(size 1.27 1.27)
					(thickness 0.15)
				)
				(justify left bottom)
				(hide yes)
			)
		)
		(property "License" "Apache-2.0"
			(at 76.835 139.7 0)
			(effects
				(font
					(size 1.27 1.27)
					(thickness 0.15)
				)
				(justify left bottom)
				(hide yes)
			)
		)
		(property "Author" "Antmicro"
			(at 79.375 139.7 0)
			(effects
				(font
					(size 1.27 1.27)
					(thickness 0.15)
				)
				(justify left bottom)
				(hide yes)
			)
		)
		(property "Val" "100n"
			(at 59.69 159.385 90)
			(effects
				(font
					(size 1.27 1.27)
					(thickness 0.15)
				)
				(justify left)
			)
		)
		(property "Voltage" "50V"
			(at 81.915 139.7 0)
			(effects
				(font
					(size 1.27 1.27)
				)
				(justify left bottom)
				(hide yes)
			)
		)
		(property "Dielectric" "X5R"
			(at 84.455 139.7 0)
			(effects
				(font
					(size 1.27 1.27)
				)
				(justify left bottom)
				(hide yes)
			)
		)
		(pin "1"
		)
		(pin "2"
		)
		(instances
			(project "sodimm-ddr5-tester"
				(path ""
					(reference "C80")
					(unit 1)
				)
			)
		)
	)
	(symbol
		(lib_id "antmicropower:GND")
		(at 73.66 190.5 0)
		(unit 1)
		(exclude_from_sim no)
		(in_bom yes)
		(on_board yes)
		(dnp no)
		(fields_autoplaced yes)
		(property "Reference" "#PWR093"
			(at 73.66 196.85 0)
			(effects
				(font
					(size 1.27 1.27)
				)
				(hide yes)
			)
		)
		(property "Value" "GND"
			(at 76.2 191.77 0)
			(effects
				(font
					(size 1.27 1.27)
					(thickness 0.15)
				)
				(justify left)
			)
		)
		(property "Footprint" ""
			(at 82.55 198.12 0)
			(effects
				(font
					(size 1.27 1.27)
					(thickness 0.15)
				)
				(justify left bottom)
				(hide yes)
			)
		)
		(property "Datasheet" ""
			(at 82.55 203.2 0)
			(effects
				(font
					(size 1.27 1.27)
					(thickness 0.15)
				)
				(justify left bottom)
				(hide yes)
			)
		)
		(property "Description" ""
			(at 82.55 205.74 0)
			(effects
				(font
					(size 1.27 1.27)
				)
				(justify left bottom)
				(hide yes)
			)
		)
		(property "Author" "Antmicro"
			(at 82.55 198.12 0)
			(effects
				(font
					(size 1.27 1.27)
					(thickness 0.15)
				)
				(justify left bottom)
				(hide yes)
			)
		)
		(property "License" "Apache-2.0"
			(at 82.55 200.66 0)
			(effects
				(font
					(size 1.27 1.27)
					(thickness 0.15)
				)
				(justify left bottom)
				(hide yes)
			)
		)
		(pin "1"
		)
		(instances
			(project "sodimm-ddr5-tester"
				(path ""
					(reference "#PWR093")
					(unit 1)
				)
			)
		)
	)
	(symbol
		(lib_id "antmicroResistors0402:R_100R_0402")
		(at 293.37 101.6 90)
		(unit 1)
		(exclude_from_sim no)
		(in_bom yes)
		(on_board yes)
		(dnp no)
		(fields_autoplaced yes)
		(property "Reference" "R39"
			(at 295.275 97.79 90)
			(effects
				(font
					(size 1.27 1.27)
				)
				(justify right)
			)
		)
		(property "Value" "R_100R_0402"
			(at 306.07 81.28 0)
			(effects
				(font
					(size 1.27 1.27)
					(thickness 0.15)
				)
				(justify left bottom)
				(hide yes)
			)
		)
		(property "Footprint" "antmicro-footprints:R_0402_1005Metric"
			(at 308.61 81.28 0)
			(effects
				(font
					(size 1.27 1.27)
					(thickness 0.15)
				)
				(justify left bottom)
				(hide yes)
			)
		)
		(property "Datasheet" "https://www.bourns.com/docs/product-datasheets/cr.pdf"
			(at 311.15 81.28 0)
			(effects
				(font
					(size 1.27 1.27)
					(thickness 0.15)
				)
				(justify left bottom)
				(hide yes)
			)
		)
		(property "Description" ""
			(at 293.37 101.6 0)
			(effects
				(font
					(size 1.27 1.27)
				)
			)
		)
		(property "Manufacturer" "Bourns"
			(at 316.23 81.28 0)
			(effects
				(font
					(size 1.27 1.27)
					(thickness 0.15)
				)
				(justify left bottom)
				(hide yes)
			)
		)
		(property "MPN" "CR0402-FX-1000GLF"
			(at 313.69 81.28 0)
			(effects
				(font
					(size 1.27 1.27)
					(thickness 0.15)
				)
				(justify left bottom)
				(hide yes)
			)
		)
		(property "Val" "100R"
			(at 295.275 100.9649 90)
			(effects
				(font
					(size 1.27 1.27)
					(thickness 0.15)
				)
				(justify right)
			)
		)
		(property "License" "Apache-2.0"
			(at 318.77 81.28 0)
			(effects
				(font
					(size 1.27 1.27)
					(thickness 0.15)
				)
				(justify left bottom)
				(hide yes)
			)
		)
		(property "Author" "Antmicro"
			(at 321.31 81.28 0)
			(effects
				(font
					(size 1.27 1.27)
					(thickness 0.15)
				)
				(justify left bottom)
				(hide yes)
			)
		)
		(property "Tolerance" "1%"
			(at 303.53 81.28 0)
			(effects
				(font
					(size 1.27 1.27)
				)
				(justify left bottom)
				(hide yes)
			)
		)
		(pin "1"
		)
		(pin "2"
		)
		(instances
			(project "sodimm-ddr5-tester"
				(path ""
					(reference "R39")
					(unit 1)
				)
			)
		)
	)
	(symbol
		(lib_id "antmicroCapacitors0402:C_100n_0402")
		(at 52.07 247.65 90)
		(unit 1)
		(exclude_from_sim no)
		(in_bom yes)
		(on_board yes)
		(dnp no)
		(property "Reference" "C28"
			(at 52.705 243.205 90)
			(effects
				(font
					(size 1.27 1.27)
					(thickness 0.15)
				)
				(justify right)
			)
		)
		(property "Value" "C_100n_0402"
			(at 62.23 227.33 0)
			(effects
				(font
					(size 1.27 1.27)
					(thickness 0.15)
				)
				(justify left bottom)
				(hide yes)
			)
		)
		(property "Footprint" "antmicro-footprints:C_0402_1005Metric"
			(at 64.77 227.33 0)
			(effects
				(font
					(size 1.27 1.27)
					(thickness 0.15)
				)
				(justify left bottom)
				(hide yes)
			)
		)
		(property "Datasheet" "https://www.murata.com/products/productdetail?partno=GRM155R61H104KE14%23"
			(at 67.31 227.33 0)
			(effects
				(font
					(size 1.27 1.27)
					(thickness 0.15)
				)
				(justify left bottom)
				(hide yes)
			)
		)
		(property "Description" ""
			(at 52.07 247.65 0)
			(effects
				(font
					(size 1.27 1.27)
				)
			)
		)
		(property "MPN" "GRM155R61H104KE14D"
			(at 69.85 227.33 0)
			(effects
				(font
					(size 1.27 1.27)
					(thickness 0.15)
				)
				(justify left bottom)
				(hide yes)
			)
		)
		(property "Manufacturer" "Murata"
			(at 72.39 227.33 0)
			(effects
				(font
					(size 1.27 1.27)
					(thickness 0.15)
				)
				(justify left bottom)
				(hide yes)
			)
		)
		(property "License" "Apache-2.0"
			(at 74.93 227.33 0)
			(effects
				(font
					(size 1.27 1.27)
					(thickness 0.15)
				)
				(justify left bottom)
				(hide yes)
			)
		)
		(property "Author" "Antmicro"
			(at 77.47 227.33 0)
			(effects
				(font
					(size 1.27 1.27)
					(thickness 0.15)
				)
				(justify left bottom)
				(hide yes)
			)
		)
		(property "Val" "100n"
			(at 52.705 247.015 90)
			(effects
				(font
					(size 1.27 1.27)
					(thickness 0.15)
				)
				(justify right)
			)
		)
		(property "Voltage" "50V"
			(at 80.01 227.33 0)
			(effects
				(font
					(size 1.27 1.27)
				)
				(justify left bottom)
				(hide yes)
			)
		)
		(property "Dielectric" "X5R"
			(at 82.55 227.33 0)
			(effects
				(font
					(size 1.27 1.27)
				)
				(justify left bottom)
				(hide yes)
			)
		)
		(pin "1"
		)
		(pin "2"
		)
		(instances
			(project "sodimm-ddr5-tester"
				(path ""
					(reference "C28")
					(unit 1)
				)
			)
		)
	)
	(symbol
		(lib_id "antmicropower:GND")
		(at 129.54 222.25 0)
		(unit 1)
		(exclude_from_sim no)
		(in_bom yes)
		(on_board yes)
		(dnp no)
		(fields_autoplaced yes)
		(property "Reference" "#PWR0139"
			(at 129.54 228.6 0)
			(effects
				(font
					(size 1.27 1.27)
				)
				(hide yes)
			)
		)
		(property "Value" "GND"
			(at 132.08 223.52 0)
			(effects
				(font
					(size 1.27 1.27)
					(thickness 0.15)
				)
				(justify left)
			)
		)
		(property "Footprint" ""
			(at 138.43 229.87 0)
			(effects
				(font
					(size 1.27 1.27)
					(thickness 0.15)
				)
				(justify left bottom)
				(hide yes)
			)
		)
		(property "Datasheet" ""
			(at 138.43 234.95 0)
			(effects
				(font
					(size 1.27 1.27)
					(thickness 0.15)
				)
				(justify left bottom)
				(hide yes)
			)
		)
		(property "Description" ""
			(at 138.43 237.49 0)
			(effects
				(font
					(size 1.27 1.27)
				)
				(justify left bottom)
				(hide yes)
			)
		)
		(property "Author" "Antmicro"
			(at 138.43 229.87 0)
			(effects
				(font
					(size 1.27 1.27)
					(thickness 0.15)
				)
				(justify left bottom)
				(hide yes)
			)
		)
		(property "License" "Apache-2.0"
			(at 138.43 232.41 0)
			(effects
				(font
					(size 1.27 1.27)
					(thickness 0.15)
				)
				(justify left bottom)
				(hide yes)
			)
		)
		(pin "1"
		)
		(instances
			(project "sodimm-ddr5-tester"
				(path ""
					(reference "#PWR0139")
					(unit 1)
				)
			)
		)
	)
	(symbol
		(lib_id "antmicroCapacitors0402:C_100n_0402")
		(at 73.66 189.23 90)
		(unit 1)
		(exclude_from_sim no)
		(in_bom yes)
		(on_board yes)
		(dnp no)
		(property "Reference" "C46"
			(at 74.295 184.785 90)
			(effects
				(font
					(size 1.27 1.27)
					(thickness 0.15)
				)
				(justify right)
			)
		)
		(property "Value" "C_100n_0402"
			(at 83.82 168.91 0)
			(effects
				(font
					(size 1.27 1.27)
					(thickness 0.15)
				)
				(justify left bottom)
				(hide yes)
			)
		)
		(property "Footprint" "antmicro-footprints:C_0402_1005Metric"
			(at 86.36 168.91 0)
			(effects
				(font
					(size 1.27 1.27)
					(thickness 0.15)
				)
				(justify left bottom)
				(hide yes)
			)
		)
		(property "Datasheet" "https://www.murata.com/products/productdetail?partno=GRM155R61H104KE14%23"
			(at 88.9 168.91 0)
			(effects
				(font
					(size 1.27 1.27)
					(thickness 0.15)
				)
				(justify left bottom)
				(hide yes)
			)
		)
		(property "Description" ""
			(at 73.66 189.23 0)
			(effects
				(font
					(size 1.27 1.27)
				)
			)
		)
		(property "MPN" "GRM155R61H104KE14D"
			(at 91.44 168.91 0)
			(effects
				(font
					(size 1.27 1.27)
					(thickness 0.15)
				)
				(justify left bottom)
				(hide yes)
			)
		)
		(property "Manufacturer" "Murata"
			(at 93.98 168.91 0)
			(effects
				(font
					(size 1.27 1.27)
					(thickness 0.15)
				)
				(justify left bottom)
				(hide yes)
			)
		)
		(property "License" "Apache-2.0"
			(at 96.52 168.91 0)
			(effects
				(font
					(size 1.27 1.27)
					(thickness 0.15)
				)
				(justify left bottom)
				(hide yes)
			)
		)
		(property "Author" "Antmicro"
			(at 99.06 168.91 0)
			(effects
				(font
					(size 1.27 1.27)
					(thickness 0.15)
				)
				(justify left bottom)
				(hide yes)
			)
		)
		(property "Val" "100n"
			(at 74.295 188.595 90)
			(effects
				(font
					(size 1.27 1.27)
					(thickness 0.15)
				)
				(justify right)
			)
		)
		(property "Voltage" "50V"
			(at 101.6 168.91 0)
			(effects
				(font
					(size 1.27 1.27)
				)
				(justify left bottom)
				(hide yes)
			)
		)
		(property "Dielectric" "X5R"
			(at 104.14 168.91 0)
			(effects
				(font
					(size 1.27 1.27)
				)
				(justify left bottom)
				(hide yes)
			)
		)
		(pin "1"
		)
		(pin "2"
		)
		(instances
			(project "sodimm-ddr5-tester"
				(path ""
					(reference "C46")
					(unit 1)
				)
			)
		)
	)
	(symbol
		(lib_id "antmicroCapacitors0402:C_100n_0402")
		(at 144.145 160.655 90)
		(unit 1)
		(exclude_from_sim no)
		(in_bom yes)
		(on_board yes)
		(dnp no)
		(property "Reference" "C37"
			(at 144.78 156.21 90)
			(effects
				(font
					(size 1.27 1.27)
					(thickness 0.15)
				)
				(justify right)
			)
		)
		(property "Value" "C_100n_0402"
			(at 154.305 140.335 0)
			(effects
				(font
					(size 1.27 1.27)
					(thickness 0.15)
				)
				(justify left bottom)
				(hide yes)
			)
		)
		(property "Footprint" "antmicro-footprints:C_0402_1005Metric"
			(at 156.845 140.335 0)
			(effects
				(font
					(size 1.27 1.27)
					(thickness 0.15)
				)
				(justify left bottom)
				(hide yes)
			)
		)
		(property "Datasheet" "https://www.murata.com/products/productdetail?partno=GRM155R61H104KE14%23"
			(at 159.385 140.335 0)
			(effects
				(font
					(size 1.27 1.27)
					(thickness 0.15)
				)
				(justify left bottom)
				(hide yes)
			)
		)
		(property "Description" ""
			(at 144.145 160.655 0)
			(effects
				(font
					(size 1.27 1.27)
				)
			)
		)
		(property "MPN" "GRM155R61H104KE14D"
			(at 161.925 140.335 0)
			(effects
				(font
					(size 1.27 1.27)
					(thickness 0.15)
				)
				(justify left bottom)
				(hide yes)
			)
		)
		(property "Manufacturer" "Murata"
			(at 164.465 140.335 0)
			(effects
				(font
					(size 1.27 1.27)
					(thickness 0.15)
				)
				(justify left bottom)
				(hide yes)
			)
		)
		(property "License" "Apache-2.0"
			(at 167.005 140.335 0)
			(effects
				(font
					(size 1.27 1.27)
					(thickness 0.15)
				)
				(justify left bottom)
				(hide yes)
			)
		)
		(property "Author" "Antmicro"
			(at 169.545 140.335 0)
			(effects
				(font
					(size 1.27 1.27)
					(thickness 0.15)
				)
				(justify left bottom)
				(hide yes)
			)
		)
		(property "Val" "100n"
			(at 144.78 160.02 90)
			(effects
				(font
					(size 1.27 1.27)
					(thickness 0.15)
				)
				(justify right)
			)
		)
		(property "Voltage" "50V"
			(at 172.085 140.335 0)
			(effects
				(font
					(size 1.27 1.27)
				)
				(justify left bottom)
				(hide yes)
			)
		)
		(property "Dielectric" "X5R"
			(at 174.625 140.335 0)
			(effects
				(font
					(size 1.27 1.27)
				)
				(justify left bottom)
				(hide yes)
			)
		)
		(pin "1"
		)
		(pin "2"
		)
		(instances
			(project "sodimm-ddr5-tester"
				(path ""
					(reference "C37")
					(unit 1)
				)
			)
		)
	)
	(symbol
		(lib_id "antmicroCapacitors0603:C_47u_0603")
		(at 38.735 154.94 270)
		(unit 1)
		(exclude_from_sim no)
		(in_bom yes)
		(on_board yes)
		(dnp no)
		(property "Reference" "C73"
			(at 39.37 155.575 90)
			(effects
				(font
					(size 1.27 1.27)
				)
				(justify left)
			)
		)
		(property "Value" "C_47u_0603"
			(at 28.575 175.26 0)
			(effects
				(font
					(size 1.27 1.27)
					(thickness 0.15)
				)
				(justify left bottom)
				(hide yes)
			)
		)
		(property "Footprint" "antmicro-footprints:C_0603_1608Metric"
			(at 26.035 175.26 0)
			(effects
				(font
					(size 1.27 1.27)
					(thickness 0.15)
				)
				(justify left bottom)
				(hide yes)
			)
		)
		(property "Datasheet" "https://www.murata.com/products/productdetail?partno=GRM188R60J476ME15%23"
			(at 23.495 175.26 0)
			(effects
				(font
					(size 1.27 1.27)
					(thickness 0.15)
				)
				(justify left bottom)
				(hide yes)
			)
		)
		(property "Description" ""
			(at 38.735 154.94 0)
			(effects
				(font
					(size 1.27 1.27)
				)
			)
		)
		(property "Manufacturer" "Murata"
			(at 18.415 175.26 0)
			(effects
				(font
					(size 1.27 1.27)
					(thickness 0.15)
				)
				(justify left bottom)
				(hide yes)
			)
		)
		(property "MPN" "GRM188R60J476ME15D"
			(at 20.955 175.26 0)
			(effects
				(font
					(size 1.27 1.27)
					(thickness 0.15)
				)
				(justify left bottom)
				(hide yes)
			)
		)
		(property "Val" "47u"
			(at 38.735 159.385 90)
			(effects
				(font
					(size 1.27 1.27)
					(thickness 0.15)
				)
				(justify left)
			)
		)
		(property "License" "Apache-2.0"
			(at 15.875 175.26 0)
			(effects
				(font
					(size 1.27 1.27)
					(thickness 0.15)
				)
				(justify left bottom)
				(hide yes)
			)
		)
		(property "Author" "Antmicro"
			(at 13.335 175.26 0)
			(effects
				(font
					(size 1.27 1.27)
					(thickness 0.15)
				)
				(justify left bottom)
				(hide yes)
			)
		)
		(property "Voltage" ""
			(at 10.795 175.26 0)
			(effects
				(font
					(size 1.27 1.27)
				)
				(justify left bottom)
				(hide yes)
			)
		)
		(property "Dielectric" ""
			(at 8.255 175.26 0)
			(effects
				(font
					(size 1.27 1.27)
				)
				(justify left bottom)
				(hide yes)
			)
		)
		(pin "1"
		)
		(pin "2"
		)
		(instances
			(project "sodimm-ddr5-tester"
				(path ""
					(reference "C73")
					(unit 1)
				)
			)
		)
	)
	(symbol
		(lib_id "antmicroCapacitors0402:C_100n_0402")
		(at 64.135 93.345 90)
		(unit 1)
		(exclude_from_sim no)
		(in_bom yes)
		(on_board yes)
		(dnp no)
		(property "Reference" "C33"
			(at 64.77 88.9 90)
			(effects
				(font
					(size 1.27 1.27)
					(thickness 0.15)
				)
				(justify right)
			)
		)
		(property "Value" "C_100n_0402"
			(at 74.295 73.025 0)
			(effects
				(font
					(size 1.27 1.27)
					(thickness 0.15)
				)
				(justify left bottom)
				(hide yes)
			)
		)
		(property "Footprint" "antmicro-footprints:C_0402_1005Metric"
			(at 76.835 73.025 0)
			(effects
				(font
					(size 1.27 1.27)
					(thickness 0.15)
				)
				(justify left bottom)
				(hide yes)
			)
		)
		(property "Datasheet" "https://www.murata.com/products/productdetail?partno=GRM155R61H104KE14%23"
			(at 79.375 73.025 0)
			(effects
				(font
					(size 1.27 1.27)
					(thickness 0.15)
				)
				(justify left bottom)
				(hide yes)
			)
		)
		(property "Description" ""
			(at 64.135 93.345 0)
			(effects
				(font
					(size 1.27 1.27)
				)
			)
		)
		(property "MPN" "GRM155R61H104KE14D"
			(at 81.915 73.025 0)
			(effects
				(font
					(size 1.27 1.27)
					(thickness 0.15)
				)
				(justify left bottom)
				(hide yes)
			)
		)
		(property "Manufacturer" "Murata"
			(at 84.455 73.025 0)
			(effects
				(font
					(size 1.27 1.27)
					(thickness 0.15)
				)
				(justify left bottom)
				(hide yes)
			)
		)
		(property "License" "Apache-2.0"
			(at 86.995 73.025 0)
			(effects
				(font
					(size 1.27 1.27)
					(thickness 0.15)
				)
				(justify left bottom)
				(hide yes)
			)
		)
		(property "Author" "Antmicro"
			(at 89.535 73.025 0)
			(effects
				(font
					(size 1.27 1.27)
					(thickness 0.15)
				)
				(justify left bottom)
				(hide yes)
			)
		)
		(property "Val" "100n"
			(at 64.77 92.71 90)
			(effects
				(font
					(size 1.27 1.27)
					(thickness 0.15)
				)
				(justify right)
			)
		)
		(property "Voltage" "50V"
			(at 92.075 73.025 0)
			(effects
				(font
					(size 1.27 1.27)
				)
				(justify left bottom)
				(hide yes)
			)
		)
		(property "Dielectric" "X5R"
			(at 94.615 73.025 0)
			(effects
				(font
					(size 1.27 1.27)
				)
				(justify left bottom)
				(hide yes)
			)
		)
		(pin "1"
		)
		(pin "2"
		)
		(instances
			(project "sodimm-ddr5-tester"
				(path ""
					(reference "C33")
					(unit 1)
				)
			)
		)
	)
	(symbol
		(lib_id "antmicroCapacitors0603:C_47u_0603")
		(at 116.205 184.15 270)
		(unit 1)
		(exclude_from_sim no)
		(in_bom yes)
		(on_board yes)
		(dnp no)
		(property "Reference" "C60"
			(at 116.205 184.785 90)
			(effects
				(font
					(size 1.27 1.27)
				)
				(justify left)
			)
		)
		(property "Value" "C_47u_0603"
			(at 106.045 204.47 0)
			(effects
				(font
					(size 1.27 1.27)
					(thickness 0.15)
				)
				(justify left bottom)
				(hide yes)
			)
		)
		(property "Footprint" "antmicro-footprints:C_0603_1608Metric"
			(at 103.505 204.47 0)
			(effects
				(font
					(size 1.27 1.27)
					(thickness 0.15)
				)
				(justify left bottom)
				(hide yes)
			)
		)
		(property "Datasheet" "https://www.murata.com/products/productdetail?partno=GRM188R60J476ME15%23"
			(at 100.965 204.47 0)
			(effects
				(font
					(size 1.27 1.27)
					(thickness 0.15)
				)
				(justify left bottom)
				(hide yes)
			)
		)
		(property "Description" ""
			(at 116.205 184.15 0)
			(effects
				(font
					(size 1.27 1.27)
				)
			)
		)
		(property "Manufacturer" "Murata"
			(at 95.885 204.47 0)
			(effects
				(font
					(size 1.27 1.27)
					(thickness 0.15)
				)
				(justify left bottom)
				(hide yes)
			)
		)
		(property "MPN" "GRM188R60J476ME15D"
			(at 98.425 204.47 0)
			(effects
				(font
					(size 1.27 1.27)
					(thickness 0.15)
				)
				(justify left bottom)
				(hide yes)
			)
		)
		(property "Val" "47u"
			(at 116.205 188.595 90)
			(effects
				(font
					(size 1.27 1.27)
					(thickness 0.15)
				)
				(justify left)
			)
		)
		(property "License" "Apache-2.0"
			(at 93.345 204.47 0)
			(effects
				(font
					(size 1.27 1.27)
					(thickness 0.15)
				)
				(justify left bottom)
				(hide yes)
			)
		)
		(property "Author" "Antmicro"
			(at 90.805 204.47 0)
			(effects
				(font
					(size 1.27 1.27)
					(thickness 0.15)
				)
				(justify left bottom)
				(hide yes)
			)
		)
		(property "Voltage" ""
			(at 88.265 204.47 0)
			(effects
				(font
					(size 1.27 1.27)
				)
				(justify left bottom)
				(hide yes)
			)
		)
		(property "Dielectric" ""
			(at 85.725 204.47 0)
			(effects
				(font
					(size 1.27 1.27)
				)
				(justify left bottom)
				(hide yes)
			)
		)
		(pin "1"
		)
		(pin "2"
		)
		(instances
			(project "sodimm-ddr5-tester"
				(path ""
					(reference "C60")
					(unit 1)
				)
			)
		)
	)
	(symbol
		(lib_id "antmicropower:GND")
		(at 59.69 190.5 0)
		(unit 1)
		(exclude_from_sim no)
		(in_bom yes)
		(on_board yes)
		(dnp no)
		(fields_autoplaced yes)
		(property "Reference" "#PWR082"
			(at 59.69 196.85 0)
			(effects
				(font
					(size 1.27 1.27)
				)
				(hide yes)
			)
		)
		(property "Value" "GND"
			(at 62.23 191.77 0)
			(effects
				(font
					(size 1.27 1.27)
					(thickness 0.15)
				)
				(justify left)
			)
		)
		(property "Footprint" ""
			(at 68.58 198.12 0)
			(effects
				(font
					(size 1.27 1.27)
					(thickness 0.15)
				)
				(justify left bottom)
				(hide yes)
			)
		)
		(property "Datasheet" ""
			(at 68.58 203.2 0)
			(effects
				(font
					(size 1.27 1.27)
					(thickness 0.15)
				)
				(justify left bottom)
				(hide yes)
			)
		)
		(property "Description" ""
			(at 68.58 205.74 0)
			(effects
				(font
					(size 1.27 1.27)
				)
				(justify left bottom)
				(hide yes)
			)
		)
		(property "Author" "Antmicro"
			(at 68.58 198.12 0)
			(effects
				(font
					(size 1.27 1.27)
					(thickness 0.15)
				)
				(justify left bottom)
				(hide yes)
			)
		)
		(property "License" "Apache-2.0"
			(at 68.58 200.66 0)
			(effects
				(font
					(size 1.27 1.27)
					(thickness 0.15)
				)
				(justify left bottom)
				(hide yes)
			)
		)
		(pin "1"
		)
		(instances
			(project "sodimm-ddr5-tester"
				(path ""
					(reference "#PWR082")
					(unit 1)
				)
			)
		)
	)
	(symbol
		(lib_id "antmicropower:+1V0_MGTAVCC")
		(at 288.29 80.645 0)
		(unit 1)
		(exclude_from_sim no)
		(in_bom yes)
		(on_board yes)
		(dnp no)
		(fields_autoplaced yes)
		(property "Reference" "#PWR0159"
			(at 288.29 84.455 0)
			(effects
				(font
					(size 1.27 1.27)
				)
				(hide yes)
			)
		)
		(property "Value" "+1V0_MGTAVCC"
			(at 288.29 76.835 0)
			(effects
				(font
					(size 1.27 1.27)
				)
			)
		)
		(property "Footprint" ""
			(at 288.29 80.645 0)
			(effects
				(font
					(size 1.27 1.27)
				)
				(hide yes)
			)
		)
		(property "Datasheet" ""
			(at 288.29 80.645 0)
			(effects
				(font
					(size 1.27 1.27)
				)
				(hide yes)
			)
		)
		(property "Description" ""
			(at 288.29 80.645 0)
			(effects
				(font
					(size 1.27 1.27)
				)
			)
		)
		(pin "1"
		)
		(instances
			(project "sodimm-ddr5-tester"
				(path ""
					(reference "#PWR0159")
					(unit 1)
				)
			)
		)
	)
	(symbol
		(lib_id "antmicroCapacitors0402:C_100n_0402")
		(at 367.03 125.73 90)
		(unit 1)
		(exclude_from_sim no)
		(in_bom yes)
		(on_board yes)
		(dnp no)
		(property "Reference" "C108"
			(at 367.665 121.285 90)
			(effects
				(font
					(size 1.27 1.27)
					(thickness 0.15)
				)
				(justify right)
			)
		)
		(property "Value" "C_100n_0402"
			(at 377.19 105.41 0)
			(effects
				(font
					(size 1.27 1.27)
					(thickness 0.15)
				)
				(justify left bottom)
				(hide yes)
			)
		)
		(property "Footprint" "antmicro-footprints:C_0402_1005Metric"
			(at 379.73 105.41 0)
			(effects
				(font
					(size 1.27 1.27)
					(thickness 0.15)
				)
				(justify left bottom)
				(hide yes)
			)
		)
		(property "Datasheet" "https://www.murata.com/products/productdetail?partno=GRM155R61H104KE14%23"
			(at 382.27 105.41 0)
			(effects
				(font
					(size 1.27 1.27)
					(thickness 0.15)
				)
				(justify left bottom)
				(hide yes)
			)
		)
		(property "Description" ""
			(at 367.03 125.73 0)
			(effects
				(font
					(size 1.27 1.27)
				)
			)
		)
		(property "MPN" "GRM155R61H104KE14D"
			(at 384.81 105.41 0)
			(effects
				(font
					(size 1.27 1.27)
					(thickness 0.15)
				)
				(justify left bottom)
				(hide yes)
			)
		)
		(property "Manufacturer" "Murata"
			(at 387.35 105.41 0)
			(effects
				(font
					(size 1.27 1.27)
					(thickness 0.15)
				)
				(justify left bottom)
				(hide yes)
			)
		)
		(property "License" "Apache-2.0"
			(at 389.89 105.41 0)
			(effects
				(font
					(size 1.27 1.27)
					(thickness 0.15)
				)
				(justify left bottom)
				(hide yes)
			)
		)
		(property "Author" "Antmicro"
			(at 392.43 105.41 0)
			(effects
				(font
					(size 1.27 1.27)
					(thickness 0.15)
				)
				(justify left bottom)
				(hide yes)
			)
		)
		(property "Val" "100n"
			(at 367.665 125.095 90)
			(effects
				(font
					(size 1.27 1.27)
					(thickness 0.15)
				)
				(justify right)
			)
		)
		(property "Voltage" "50V"
			(at 394.97 105.41 0)
			(effects
				(font
					(size 1.27 1.27)
				)
				(justify left bottom)
				(hide yes)
			)
		)
		(property "Dielectric" "X5R"
			(at 397.51 105.41 0)
			(effects
				(font
					(size 1.27 1.27)
				)
				(justify left bottom)
				(hide yes)
			)
		)
		(pin "1"
		)
		(pin "2"
		)
		(instances
			(project "sodimm-ddr5-tester"
				(path ""
					(reference "C108")
					(unit 1)
				)
			)
		)
	)
	(symbol
		(lib_id "antmicropower:GND")
		(at 116.205 162.56 0)
		(unit 1)
		(exclude_from_sim no)
		(in_bom yes)
		(on_board yes)
		(dnp no)
		(fields_autoplaced yes)
		(property "Reference" "#PWR058"
			(at 116.205 168.91 0)
			(effects
				(font
					(size 1.27 1.27)
				)
				(hide yes)
			)
		)
		(property "Value" "GND"
			(at 118.11 163.83 0)
			(effects
				(font
					(size 1.27 1.27)
					(thickness 0.15)
				)
				(justify left)
			)
		)
		(property "Footprint" ""
			(at 125.095 170.18 0)
			(effects
				(font
					(size 1.27 1.27)
					(thickness 0.15)
				)
				(justify left bottom)
				(hide yes)
			)
		)
		(property "Datasheet" ""
			(at 125.095 175.26 0)
			(effects
				(font
					(size 1.27 1.27)
					(thickness 0.15)
				)
				(justify left bottom)
				(hide yes)
			)
		)
		(property "Description" ""
			(at 125.095 177.8 0)
			(effects
				(font
					(size 1.27 1.27)
				)
				(justify left bottom)
				(hide yes)
			)
		)
		(property "Author" "Antmicro"
			(at 125.095 170.18 0)
			(effects
				(font
					(size 1.27 1.27)
					(thickness 0.15)
				)
				(justify left bottom)
				(hide yes)
			)
		)
		(property "License" "Apache-2.0"
			(at 125.095 172.72 0)
			(effects
				(font
					(size 1.27 1.27)
					(thickness 0.15)
				)
				(justify left bottom)
				(hide yes)
			)
		)
		(pin "1"
		)
		(instances
			(project "sodimm-ddr5-tester"
				(path ""
					(reference "#PWR058")
					(unit 1)
				)
			)
		)
	)
	(symbol
		(lib_id "antmicroCapacitors0402:C_100n_0402")
		(at 163.83 93.345 90)
		(unit 1)
		(exclude_from_sim no)
		(in_bom yes)
		(on_board yes)
		(dnp no)
		(property "Reference" "C90"
			(at 164.465 88.9 90)
			(effects
				(font
					(size 1.27 1.27)
					(thickness 0.15)
				)
				(justify right)
			)
		)
		(property "Value" "C_100n_0402"
			(at 173.99 73.025 0)
			(effects
				(font
					(size 1.27 1.27)
					(thickness 0.15)
				)
				(justify left bottom)
				(hide yes)
			)
		)
		(property "Footprint" "antmicro-footprints:C_0402_1005Metric"
			(at 176.53 73.025 0)
			(effects
				(font
					(size 1.27 1.27)
					(thickness 0.15)
				)
				(justify left bottom)
				(hide yes)
			)
		)
		(property "Datasheet" "https://www.murata.com/products/productdetail?partno=GRM155R61H104KE14%23"
			(at 179.07 73.025 0)
			(effects
				(font
					(size 1.27 1.27)
					(thickness 0.15)
				)
				(justify left bottom)
				(hide yes)
			)
		)
		(property "Description" ""
			(at 163.83 93.345 0)
			(effects
				(font
					(size 1.27 1.27)
				)
			)
		)
		(property "MPN" "GRM155R61H104KE14D"
			(at 181.61 73.025 0)
			(effects
				(font
					(size 1.27 1.27)
					(thickness 0.15)
				)
				(justify left bottom)
				(hide yes)
			)
		)
		(property "Manufacturer" "Murata"
			(at 184.15 73.025 0)
			(effects
				(font
					(size 1.27 1.27)
					(thickness 0.15)
				)
				(justify left bottom)
				(hide yes)
			)
		)
		(property "License" "Apache-2.0"
			(at 186.69 73.025 0)
			(effects
				(font
					(size 1.27 1.27)
					(thickness 0.15)
				)
				(justify left bottom)
				(hide yes)
			)
		)
		(property "Author" "Antmicro"
			(at 189.23 73.025 0)
			(effects
				(font
					(size 1.27 1.27)
					(thickness 0.15)
				)
				(justify left bottom)
				(hide yes)
			)
		)
		(property "Val" "100n"
			(at 164.465 92.71 90)
			(effects
				(font
					(size 1.27 1.27)
					(thickness 0.15)
				)
				(justify right)
			)
		)
		(property "Voltage" "50V"
			(at 191.77 73.025 0)
			(effects
				(font
					(size 1.27 1.27)
				)
				(justify left bottom)
				(hide yes)
			)
		)
		(property "Dielectric" "X5R"
			(at 194.31 73.025 0)
			(effects
				(font
					(size 1.27 1.27)
				)
				(justify left bottom)
				(hide yes)
			)
		)
		(pin "1"
		)
		(pin "2"
		)
		(instances
			(project "sodimm-ddr5-tester"
				(path ""
					(reference "C90")
					(unit 1)
				)
			)
		)
	)
	(symbol
		(lib_id "antmicroCapacitors0402:C_100n_0402")
		(at 72.39 93.345 90)
		(unit 1)
		(exclude_from_sim no)
		(in_bom yes)
		(on_board yes)
		(dnp no)
		(property "Reference" "C42"
			(at 73.025 88.9 90)
			(effects
				(font
					(size 1.27 1.27)
					(thickness 0.15)
				)
				(justify right)
			)
		)
		(property "Value" "C_100n_0402"
			(at 82.55 73.025 0)
			(effects
				(font
					(size 1.27 1.27)
					(thickness 0.15)
				)
				(justify left bottom)
				(hide yes)
			)
		)
		(property "Footprint" "antmicro-footprints:C_0402_1005Metric"
			(at 85.09 73.025 0)
			(effects
				(font
					(size 1.27 1.27)
					(thickness 0.15)
				)
				(justify left bottom)
				(hide yes)
			)
		)
		(property "Datasheet" "https://www.murata.com/products/productdetail?partno=GRM155R61H104KE14%23"
			(at 87.63 73.025 0)
			(effects
				(font
					(size 1.27 1.27)
					(thickness 0.15)
				)
				(justify left bottom)
				(hide yes)
			)
		)
		(property "Description" ""
			(at 72.39 93.345 0)
			(effects
				(font
					(size 1.27 1.27)
				)
			)
		)
		(property "MPN" "GRM155R61H104KE14D"
			(at 90.17 73.025 0)
			(effects
				(font
					(size 1.27 1.27)
					(thickness 0.15)
				)
				(justify left bottom)
				(hide yes)
			)
		)
		(property "Manufacturer" "Murata"
			(at 92.71 73.025 0)
			(effects
				(font
					(size 1.27 1.27)
					(thickness 0.15)
				)
				(justify left bottom)
				(hide yes)
			)
		)
		(property "License" "Apache-2.0"
			(at 95.25 73.025 0)
			(effects
				(font
					(size 1.27 1.27)
					(thickness 0.15)
				)
				(justify left bottom)
				(hide yes)
			)
		)
		(property "Author" "Antmicro"
			(at 97.79 73.025 0)
			(effects
				(font
					(size 1.27 1.27)
					(thickness 0.15)
				)
				(justify left bottom)
				(hide yes)
			)
		)
		(property "Val" "100n"
			(at 73.025 92.71 90)
			(effects
				(font
					(size 1.27 1.27)
					(thickness 0.15)
				)
				(justify right)
			)
		)
		(property "Voltage" "50V"
			(at 100.33 73.025 0)
			(effects
				(font
					(size 1.27 1.27)
				)
				(justify left bottom)
				(hide yes)
			)
		)
		(property "Dielectric" "X5R"
			(at 102.87 73.025 0)
			(effects
				(font
					(size 1.27 1.27)
				)
				(justify left bottom)
				(hide yes)
			)
		)
		(pin "1"
		)
		(pin "2"
		)
		(instances
			(project "sodimm-ddr5-tester"
				(path ""
					(reference "C42")
					(unit 1)
				)
			)
		)
	)
	(symbol
		(lib_id "antmicroCapacitors0402:C_100n_0402")
		(at 80.01 247.65 90)
		(unit 1)
		(exclude_from_sim no)
		(in_bom yes)
		(on_board yes)
		(dnp no)
		(property "Reference" "C51"
			(at 80.645 243.205 90)
			(effects
				(font
					(size 1.27 1.27)
					(thickness 0.15)
				)
				(justify right)
			)
		)
		(property "Value" "C_100n_0402"
			(at 90.17 227.33 0)
			(effects
				(font
					(size 1.27 1.27)
					(thickness 0.15)
				)
				(justify left bottom)
				(hide yes)
			)
		)
		(property "Footprint" "antmicro-footprints:C_0402_1005Metric"
			(at 92.71 227.33 0)
			(effects
				(font
					(size 1.27 1.27)
					(thickness 0.15)
				)
				(justify left bottom)
				(hide yes)
			)
		)
		(property "Datasheet" "https://www.murata.com/products/productdetail?partno=GRM155R61H104KE14%23"
			(at 95.25 227.33 0)
			(effects
				(font
					(size 1.27 1.27)
					(thickness 0.15)
				)
				(justify left bottom)
				(hide yes)
			)
		)
		(property "Description" ""
			(at 80.01 247.65 0)
			(effects
				(font
					(size 1.27 1.27)
				)
			)
		)
		(property "MPN" "GRM155R61H104KE14D"
			(at 97.79 227.33 0)
			(effects
				(font
					(size 1.27 1.27)
					(thickness 0.15)
				)
				(justify left bottom)
				(hide yes)
			)
		)
		(property "Manufacturer" "Murata"
			(at 100.33 227.33 0)
			(effects
				(font
					(size 1.27 1.27)
					(thickness 0.15)
				)
				(justify left bottom)
				(hide yes)
			)
		)
		(property "License" "Apache-2.0"
			(at 102.87 227.33 0)
			(effects
				(font
					(size 1.27 1.27)
					(thickness 0.15)
				)
				(justify left bottom)
				(hide yes)
			)
		)
		(property "Author" "Antmicro"
			(at 105.41 227.33 0)
			(effects
				(font
					(size 1.27 1.27)
					(thickness 0.15)
				)
				(justify left bottom)
				(hide yes)
			)
		)
		(property "Val" "100n"
			(at 80.645 247.015 90)
			(effects
				(font
					(size 1.27 1.27)
					(thickness 0.15)
				)
				(justify right)
			)
		)
		(property "Voltage" "50V"
			(at 107.95 227.33 0)
			(effects
				(font
					(size 1.27 1.27)
				)
				(justify left bottom)
				(hide yes)
			)
		)
		(property "Dielectric" "X5R"
			(at 110.49 227.33 0)
			(effects
				(font
					(size 1.27 1.27)
				)
				(justify left bottom)
				(hide yes)
			)
		)
		(pin "1"
		)
		(pin "2"
		)
		(instances
			(project "sodimm-ddr5-tester"
				(path ""
					(reference "C51")
					(unit 1)
				)
			)
		)
	)
	(symbol
		(lib_id "antmicroCapacitors0603:C_47u_0603")
		(at 115.57 215.265 270)
		(unit 1)
		(exclude_from_sim no)
		(in_bom yes)
		(on_board yes)
		(dnp no)
		(property "Reference" "C85"
			(at 115.57 215.9 90)
			(effects
				(font
					(size 1.27 1.27)
				)
				(justify left)
			)
		)
		(property "Value" "C_47u_0603"
			(at 105.41 235.585 0)
			(effects
				(font
					(size 1.27 1.27)
					(thickness 0.15)
				)
				(justify left bottom)
				(hide yes)
			)
		)
		(property "Footprint" "antmicro-footprints:C_0603_1608Metric"
			(at 102.87 235.585 0)
			(effects
				(font
					(size 1.27 1.27)
					(thickness 0.15)
				)
				(justify left bottom)
				(hide yes)
			)
		)
		(property "Datasheet" "https://www.murata.com/products/productdetail?partno=GRM188R60J476ME15%23"
			(at 100.33 235.585 0)
			(effects
				(font
					(size 1.27 1.27)
					(thickness 0.15)
				)
				(justify left bottom)
				(hide yes)
			)
		)
		(property "Description" ""
			(at 115.57 215.265 0)
			(effects
				(font
					(size 1.27 1.27)
				)
			)
		)
		(property "Manufacturer" "Murata"
			(at 95.25 235.585 0)
			(effects
				(font
					(size 1.27 1.27)
					(thickness 0.15)
				)
				(justify left bottom)
				(hide yes)
			)
		)
		(property "MPN" "GRM188R60J476ME15D"
			(at 97.79 235.585 0)
			(effects
				(font
					(size 1.27 1.27)
					(thickness 0.15)
				)
				(justify left bottom)
				(hide yes)
			)
		)
		(property "Val" "47u"
			(at 115.57 219.71 90)
			(effects
				(font
					(size 1.27 1.27)
					(thickness 0.15)
				)
				(justify left)
			)
		)
		(property "License" "Apache-2.0"
			(at 92.71 235.585 0)
			(effects
				(font
					(size 1.27 1.27)
					(thickness 0.15)
				)
				(justify left bottom)
				(hide yes)
			)
		)
		(property "Author" "Antmicro"
			(at 90.17 235.585 0)
			(effects
				(font
					(size 1.27 1.27)
					(thickness 0.15)
				)
				(justify left bottom)
				(hide yes)
			)
		)
		(property "Voltage" ""
			(at 87.63 235.585 0)
			(effects
				(font
					(size 1.27 1.27)
				)
				(justify left bottom)
				(hide yes)
			)
		)
		(property "Dielectric" ""
			(at 85.09 235.585 0)
			(effects
				(font
					(size 1.27 1.27)
				)
				(justify left bottom)
				(hide yes)
			)
		)
		(pin "1"
		)
		(pin "2"
		)
		(instances
			(project "sodimm-ddr5-tester"
				(path ""
					(reference "C85")
					(unit 1)
				)
			)
		)
	)
	(symbol
		(lib_id "antmicroCapacitors0402:C_100n_0402")
		(at 39.37 93.345 90)
		(unit 1)
		(exclude_from_sim no)
		(in_bom yes)
		(on_board yes)
		(dnp no)
		(property "Reference" "C13"
			(at 40.005 88.9 90)
			(effects
				(font
					(size 1.27 1.27)
					(thickness 0.15)
				)
				(justify right)
			)
		)
		(property "Value" "C_100n_0402"
			(at 49.53 73.025 0)
			(effects
				(font
					(size 1.27 1.27)
					(thickness 0.15)
				)
				(justify left bottom)
				(hide yes)
			)
		)
		(property "Footprint" "antmicro-footprints:C_0402_1005Metric"
			(at 52.07 73.025 0)
			(effects
				(font
					(size 1.27 1.27)
					(thickness 0.15)
				)
				(justify left bottom)
				(hide yes)
			)
		)
		(property "Datasheet" "https://www.murata.com/products/productdetail?partno=GRM155R61H104KE14%23"
			(at 54.61 73.025 0)
			(effects
				(font
					(size 1.27 1.27)
					(thickness 0.15)
				)
				(justify left bottom)
				(hide yes)
			)
		)
		(property "Description" ""
			(at 39.37 93.345 0)
			(effects
				(font
					(size 1.27 1.27)
				)
			)
		)
		(property "MPN" "GRM155R61H104KE14D"
			(at 57.15 73.025 0)
			(effects
				(font
					(size 1.27 1.27)
					(thickness 0.15)
				)
				(justify left bottom)
				(hide yes)
			)
		)
		(property "Manufacturer" "Murata"
			(at 59.69 73.025 0)
			(effects
				(font
					(size 1.27 1.27)
					(thickness 0.15)
				)
				(justify left bottom)
				(hide yes)
			)
		)
		(property "License" "Apache-2.0"
			(at 62.23 73.025 0)
			(effects
				(font
					(size 1.27 1.27)
					(thickness 0.15)
				)
				(justify left bottom)
				(hide yes)
			)
		)
		(property "Author" "Antmicro"
			(at 64.77 73.025 0)
			(effects
				(font
					(size 1.27 1.27)
					(thickness 0.15)
				)
				(justify left bottom)
				(hide yes)
			)
		)
		(property "Val" "100n"
			(at 40.005 92.71 90)
			(effects
				(font
					(size 1.27 1.27)
					(thickness 0.15)
				)
				(justify right)
			)
		)
		(property "Voltage" "50V"
			(at 67.31 73.025 0)
			(effects
				(font
					(size 1.27 1.27)
				)
				(justify left bottom)
				(hide yes)
			)
		)
		(property "Dielectric" "X5R"
			(at 69.85 73.025 0)
			(effects
				(font
					(size 1.27 1.27)
				)
				(justify left bottom)
				(hide yes)
			)
		)
		(pin "1"
		)
		(pin "2"
		)
		(instances
			(project "sodimm-ddr5-tester"
				(path ""
					(reference "C13")
					(unit 1)
				)
			)
		)
	)
	(symbol
		(lib_id "antmicropower:+1V1")
		(at 116.205 180.34 0)
		(unit 1)
		(exclude_from_sim no)
		(in_bom yes)
		(on_board yes)
		(dnp no)
		(property "Reference" "#PWR0107"
			(at 116.205 184.15 0)
			(effects
				(font
					(size 1.27 1.27)
				)
				(hide yes)
			)
		)
		(property "Value" "+1V1"
			(at 116.205 176.784 0)
			(effects
				(font
					(size 1.27 1.27)
				)
			)
		)
		(property "Footprint" ""
			(at 116.205 180.34 0)
			(effects
				(font
					(size 1.27 1.27)
				)
				(hide yes)
			)
		)
		(property "Datasheet" ""
			(at 116.205 180.34 0)
			(effects
				(font
					(size 1.27 1.27)
				)
				(hide yes)
			)
		)
		(property "Description" ""
			(at 116.205 180.34 0)
			(effects
				(font
					(size 1.27 1.27)
				)
			)
		)
		(pin "1"
		)
		(instances
			(project "sodimm-ddr5-tester"
				(path ""
					(reference "#PWR0107")
					(unit 1)
				)
			)
		)
	)
	(symbol
		(lib_id "antmicroCapacitors0603:C_47u_0603")
		(at 46.99 116.84 270)
		(unit 1)
		(exclude_from_sim no)
		(in_bom yes)
		(on_board yes)
		(dnp no)
		(property "Reference" "C18"
			(at 46.99 117.475 90)
			(effects
				(font
					(size 1.27 1.27)
				)
				(justify left)
			)
		)
		(property "Value" "C_47u_0603"
			(at 36.83 137.16 0)
			(effects
				(font
					(size 1.27 1.27)
					(thickness 0.15)
				)
				(justify left bottom)
				(hide yes)
			)
		)
		(property "Footprint" "antmicro-footprints:C_0603_1608Metric"
			(at 34.29 137.16 0)
			(effects
				(font
					(size 1.27 1.27)
					(thickness 0.15)
				)
				(justify left bottom)
				(hide yes)
			)
		)
		(property "Datasheet" "https://www.murata.com/products/productdetail?partno=GRM188R60J476ME15%23"
			(at 31.75 137.16 0)
			(effects
				(font
					(size 1.27 1.27)
					(thickness 0.15)
				)
				(justify left bottom)
				(hide yes)
			)
		)
		(property "Description" ""
			(at 46.99 116.84 0)
			(effects
				(font
					(size 1.27 1.27)
				)
			)
		)
		(property "Manufacturer" "Murata"
			(at 26.67 137.16 0)
			(effects
				(font
					(size 1.27 1.27)
					(thickness 0.15)
				)
				(justify left bottom)
				(hide yes)
			)
		)
		(property "MPN" "GRM188R60J476ME15D"
			(at 29.21 137.16 0)
			(effects
				(font
					(size 1.27 1.27)
					(thickness 0.15)
				)
				(justify left bottom)
				(hide yes)
			)
		)
		(property "Val" "47u"
			(at 46.99 121.285 90)
			(effects
				(font
					(size 1.27 1.27)
					(thickness 0.15)
				)
				(justify left)
			)
		)
		(property "License" "Apache-2.0"
			(at 24.13 137.16 0)
			(effects
				(font
					(size 1.27 1.27)
					(thickness 0.15)
				)
				(justify left bottom)
				(hide yes)
			)
		)
		(property "Author" "Antmicro"
			(at 21.59 137.16 0)
			(effects
				(font
					(size 1.27 1.27)
					(thickness 0.15)
				)
				(justify left bottom)
				(hide yes)
			)
		)
		(property "Voltage" ""
			(at 19.05 137.16 0)
			(effects
				(font
					(size 1.27 1.27)
				)
				(justify left bottom)
				(hide yes)
			)
		)
		(property "Dielectric" ""
			(at 16.51 137.16 0)
			(effects
				(font
					(size 1.27 1.27)
				)
				(justify left bottom)
				(hide yes)
			)
		)
		(pin "1"
		)
		(pin "2"
		)
		(instances
			(project "sodimm-ddr5-tester"
				(path ""
					(reference "C18")
					(unit 1)
				)
			)
		)
	)
	(symbol
		(lib_id "antmicroCapacitors0603:C_47u_0603")
		(at 38.1 242.57 270)
		(unit 1)
		(exclude_from_sim no)
		(in_bom yes)
		(on_board yes)
		(dnp no)
		(property "Reference" "C15"
			(at 39.37 243.205 90)
			(effects
				(font
					(size 1.27 1.27)
				)
				(justify left)
			)
		)
		(property "Value" "C_47u_0603"
			(at 27.94 262.89 0)
			(effects
				(font
					(size 1.27 1.27)
					(thickness 0.15)
				)
				(justify left bottom)
				(hide yes)
			)
		)
		(property "Footprint" "antmicro-footprints:C_0603_1608Metric"
			(at 25.4 262.89 0)
			(effects
				(font
					(size 1.27 1.27)
					(thickness 0.15)
				)
				(justify left bottom)
				(hide yes)
			)
		)
		(property "Datasheet" "https://www.murata.com/products/productdetail?partno=GRM188R60J476ME15%23"
			(at 22.86 262.89 0)
			(effects
				(font
					(size 1.27 1.27)
					(thickness 0.15)
				)
				(justify left bottom)
				(hide yes)
			)
		)
		(property "Description" ""
			(at 38.1 242.57 0)
			(effects
				(font
					(size 1.27 1.27)
				)
			)
		)
		(property "Manufacturer" "Murata"
			(at 17.78 262.89 0)
			(effects
				(font
					(size 1.27 1.27)
					(thickness 0.15)
				)
				(justify left bottom)
				(hide yes)
			)
		)
		(property "MPN" "GRM188R60J476ME15D"
			(at 20.32 262.89 0)
			(effects
				(font
					(size 1.27 1.27)
					(thickness 0.15)
				)
				(justify left bottom)
				(hide yes)
			)
		)
		(property "Val" "47u"
			(at 38.1 247.015 90)
			(effects
				(font
					(size 1.27 1.27)
					(thickness 0.15)
				)
				(justify left)
			)
		)
		(property "License" "Apache-2.0"
			(at 15.24 262.89 0)
			(effects
				(font
					(size 1.27 1.27)
					(thickness 0.15)
				)
				(justify left bottom)
				(hide yes)
			)
		)
		(property "Author" "Antmicro"
			(at 12.7 262.89 0)
			(effects
				(font
					(size 1.27 1.27)
					(thickness 0.15)
				)
				(justify left bottom)
				(hide yes)
			)
		)
		(property "Voltage" ""
			(at 10.16 262.89 0)
			(effects
				(font
					(size 1.27 1.27)
				)
				(justify left bottom)
				(hide yes)
			)
		)
		(property "Dielectric" ""
			(at 7.62 262.89 0)
			(effects
				(font
					(size 1.27 1.27)
				)
				(justify left bottom)
				(hide yes)
			)
		)
		(pin "1"
		)
		(pin "2"
		)
		(instances
			(project "sodimm-ddr5-tester"
				(path ""
					(reference "C15")
					(unit 1)
				)
			)
		)
	)
	(symbol
		(lib_id "antmicroCapacitors0402:C_4u7_0402")
		(at 111.76 62.23 270)
		(unit 1)
		(exclude_from_sim no)
		(in_bom yes)
		(on_board yes)
		(dnp no)
		(property "Reference" "C62"
			(at 111.76 62.865 90)
			(effects
				(font
					(size 1.27 1.27)
				)
				(justify left)
			)
		)
		(property "Value" "C_4u7_0402"
			(at 101.6 82.55 0)
			(effects
				(font
					(size 1.27 1.27)
					(thickness 0.15)
				)
				(justify left bottom)
				(hide yes)
			)
		)
		(property "Footprint" "antmicro-footprints:C_0402_1005Metric"
			(at 99.06 82.55 0)
			(effects
				(font
					(size 1.27 1.27)
					(thickness 0.15)
				)
				(justify left bottom)
				(hide yes)
			)
		)
		(property "Datasheet" "https://www.murata.com/products/productdetail?partno=GRM155R61A475MEAA%23"
			(at 96.52 82.55 0)
			(effects
				(font
					(size 1.27 1.27)
					(thickness 0.15)
				)
				(justify left bottom)
				(hide yes)
			)
		)
		(property "Description" ""
			(at 111.76 62.23 0)
			(effects
				(font
					(size 1.27 1.27)
				)
			)
		)
		(property "Manufacturer" "Murata"
			(at 91.44 82.55 0)
			(effects
				(font
					(size 1.27 1.27)
					(thickness 0.15)
				)
				(justify left bottom)
				(hide yes)
			)
		)
		(property "MPN" "GRM155R61A475MEAAD"
			(at 93.98 82.55 0)
			(effects
				(font
					(size 1.27 1.27)
					(thickness 0.15)
				)
				(justify left bottom)
				(hide yes)
			)
		)
		(property "Val" "4u7"
			(at 111.76 66.675 90)
			(effects
				(font
					(size 1.27 1.27)
					(thickness 0.15)
				)
				(justify left)
			)
		)
		(property "License" "Apache-2.0"
			(at 88.9 82.55 0)
			(effects
				(font
					(size 1.27 1.27)
					(thickness 0.15)
				)
				(justify left bottom)
				(hide yes)
			)
		)
		(property "Author" "Antmicro"
			(at 86.36 82.55 0)
			(effects
				(font
					(size 1.27 1.27)
					(thickness 0.15)
				)
				(justify left bottom)
				(hide yes)
			)
		)
		(property "Voltage" ""
			(at 83.82 82.55 0)
			(effects
				(font
					(size 1.27 1.27)
				)
				(justify left bottom)
				(hide yes)
			)
		)
		(property "Dielectric" ""
			(at 81.28 82.55 0)
			(effects
				(font
					(size 1.27 1.27)
				)
				(justify left bottom)
				(hide yes)
			)
		)
		(pin "1"
		)
		(pin "2"
		)
		(instances
			(project "sodimm-ddr5-tester"
				(path ""
					(reference "C62")
					(unit 1)
				)
			)
		)
	)
	(symbol
		(lib_id "antmicroCapacitors0402:C_100n_0402")
		(at 66.675 189.23 90)
		(unit 1)
		(exclude_from_sim no)
		(in_bom yes)
		(on_board yes)
		(dnp no)
		(property "Reference" "C40"
			(at 67.31 184.785 90)
			(effects
				(font
					(size 1.27 1.27)
					(thickness 0.15)
				)
				(justify right)
			)
		)
		(property "Value" "C_100n_0402"
			(at 76.835 168.91 0)
			(effects
				(font
					(size 1.27 1.27)
					(thickness 0.15)
				)
				(justify left bottom)
				(hide yes)
			)
		)
		(property "Footprint" "antmicro-footprints:C_0402_1005Metric"
			(at 79.375 168.91 0)
			(effects
				(font
					(size 1.27 1.27)
					(thickness 0.15)
				)
				(justify left bottom)
				(hide yes)
			)
		)
		(property "Datasheet" "https://www.murata.com/products/productdetail?partno=GRM155R61H104KE14%23"
			(at 81.915 168.91 0)
			(effects
				(font
					(size 1.27 1.27)
					(thickness 0.15)
				)
				(justify left bottom)
				(hide yes)
			)
		)
		(property "Description" ""
			(at 66.675 189.23 0)
			(effects
				(font
					(size 1.27 1.27)
				)
			)
		)
		(property "MPN" "GRM155R61H104KE14D"
			(at 84.455 168.91 0)
			(effects
				(font
					(size 1.27 1.27)
					(thickness 0.15)
				)
				(justify left bottom)
				(hide yes)
			)
		)
		(property "Manufacturer" "Murata"
			(at 86.995 168.91 0)
			(effects
				(font
					(size 1.27 1.27)
					(thickness 0.15)
				)
				(justify left bottom)
				(hide yes)
			)
		)
		(property "License" "Apache-2.0"
			(at 89.535 168.91 0)
			(effects
				(font
					(size 1.27 1.27)
					(thickness 0.15)
				)
				(justify left bottom)
				(hide yes)
			)
		)
		(property "Author" "Antmicro"
			(at 92.075 168.91 0)
			(effects
				(font
					(size 1.27 1.27)
					(thickness 0.15)
				)
				(justify left bottom)
				(hide yes)
			)
		)
		(property "Val" "100n"
			(at 67.31 188.595 90)
			(effects
				(font
					(size 1.27 1.27)
					(thickness 0.15)
				)
				(justify right)
			)
		)
		(property "Voltage" "50V"
			(at 94.615 168.91 0)
			(effects
				(font
					(size 1.27 1.27)
				)
				(justify left bottom)
				(hide yes)
			)
		)
		(property "Dielectric" "X5R"
			(at 97.155 168.91 0)
			(effects
				(font
					(size 1.27 1.27)
				)
				(justify left bottom)
				(hide yes)
			)
		)
		(pin "1"
		)
		(pin "2"
		)
		(instances
			(project "sodimm-ddr5-tester"
				(path ""
					(reference "C40")
					(unit 1)
				)
			)
		)
	)
	(symbol
		(lib_id "antmicropower:GND")
		(at 367.03 127 0)
		(unit 1)
		(exclude_from_sim no)
		(in_bom yes)
		(on_board yes)
		(dnp no)
		(fields_autoplaced yes)
		(property "Reference" "#PWR0168"
			(at 367.03 133.35 0)
			(effects
				(font
					(size 1.27 1.27)
				)
				(hide yes)
			)
		)
		(property "Value" "GND"
			(at 369.57 128.27 0)
			(effects
				(font
					(size 1.27 1.27)
					(thickness 0.15)
				)
				(justify left)
			)
		)
		(property "Footprint" ""
			(at 375.92 134.62 0)
			(effects
				(font
					(size 1.27 1.27)
					(thickness 0.15)
				)
				(justify left bottom)
				(hide yes)
			)
		)
		(property "Datasheet" ""
			(at 375.92 139.7 0)
			(effects
				(font
					(size 1.27 1.27)
					(thickness 0.15)
				)
				(justify left bottom)
				(hide yes)
			)
		)
		(property "Description" ""
			(at 375.92 142.24 0)
			(effects
				(font
					(size 1.27 1.27)
				)
				(justify left bottom)
				(hide yes)
			)
		)
		(property "Author" "Antmicro"
			(at 375.92 134.62 0)
			(effects
				(font
					(size 1.27 1.27)
					(thickness 0.15)
				)
				(justify left bottom)
				(hide yes)
			)
		)
		(property "License" "Apache-2.0"
			(at 375.92 137.16 0)
			(effects
				(font
					(size 1.27 1.27)
					(thickness 0.15)
				)
				(justify left bottom)
				(hide yes)
			)
		)
		(pin "1"
		)
		(instances
			(project "sodimm-ddr5-tester"
				(path ""
					(reference "#PWR0168")
					(unit 1)
				)
			)
		)
	)
	(symbol
		(lib_id "antmicropower:GND")
		(at 120.65 68.58 0)
		(mirror y)
		(unit 1)
		(exclude_from_sim no)
		(in_bom yes)
		(on_board yes)
		(dnp no)
		(fields_autoplaced yes)
		(property "Reference" "#PWR0115"
			(at 120.65 74.93 0)
			(effects
				(font
					(size 1.27 1.27)
				)
				(hide yes)
			)
		)
		(property "Value" "GND"
			(at 123.19 69.85 0)
			(effects
				(font
					(size 1.27 1.27)
					(thickness 0.15)
				)
				(justify right)
			)
		)
		(property "Footprint" ""
			(at 111.76 76.2 0)
			(effects
				(font
					(size 1.27 1.27)
					(thickness 0.15)
				)
				(justify left bottom)
				(hide yes)
			)
		)
		(property "Datasheet" ""
			(at 111.76 81.28 0)
			(effects
				(font
					(size 1.27 1.27)
					(thickness 0.15)
				)
				(justify left bottom)
				(hide yes)
			)
		)
		(property "Description" ""
			(at 111.76 83.82 0)
			(effects
				(font
					(size 1.27 1.27)
				)
				(justify left bottom)
				(hide yes)
			)
		)
		(property "Author" "Antmicro"
			(at 111.76 76.2 0)
			(effects
				(font
					(size 1.27 1.27)
					(thickness 0.15)
				)
				(justify left bottom)
				(hide yes)
			)
		)
		(property "License" "Apache-2.0"
			(at 111.76 78.74 0)
			(effects
				(font
					(size 1.27 1.27)
					(thickness 0.15)
				)
				(justify left bottom)
				(hide yes)
			)
		)
		(pin "1"
		)
		(instances
			(project "sodimm-ddr5-tester"
				(path ""
					(reference "#PWR0115")
					(unit 1)
				)
			)
		)
	)
	(symbol
		(lib_id "antmicroCapacitors0402:C_100n_0402")
		(at 130.81 93.345 90)
		(unit 1)
		(exclude_from_sim no)
		(in_bom yes)
		(on_board yes)
		(dnp no)
		(property "Reference" "C79"
			(at 131.445 88.9 90)
			(effects
				(font
					(size 1.27 1.27)
					(thickness 0.15)
				)
				(justify right)
			)
		)
		(property "Value" "C_100n_0402"
			(at 140.97 73.025 0)
			(effects
				(font
					(size 1.27 1.27)
					(thickness 0.15)
				)
				(justify left bottom)
				(hide yes)
			)
		)
		(property "Footprint" "antmicro-footprints:C_0402_1005Metric"
			(at 143.51 73.025 0)
			(effects
				(font
					(size 1.27 1.27)
					(thickness 0.15)
				)
				(justify left bottom)
				(hide yes)
			)
		)
		(property "Datasheet" "https://www.murata.com/products/productdetail?partno=GRM155R61H104KE14%23"
			(at 146.05 73.025 0)
			(effects
				(font
					(size 1.27 1.27)
					(thickness 0.15)
				)
				(justify left bottom)
				(hide yes)
			)
		)
		(property "Description" ""
			(at 130.81 93.345 0)
			(effects
				(font
					(size 1.27 1.27)
				)
			)
		)
		(property "MPN" "GRM155R61H104KE14D"
			(at 148.59 73.025 0)
			(effects
				(font
					(size 1.27 1.27)
					(thickness 0.15)
				)
				(justify left bottom)
				(hide yes)
			)
		)
		(property "Manufacturer" "Murata"
			(at 151.13 73.025 0)
			(effects
				(font
					(size 1.27 1.27)
					(thickness 0.15)
				)
				(justify left bottom)
				(hide yes)
			)
		)
		(property "License" "Apache-2.0"
			(at 153.67 73.025 0)
			(effects
				(font
					(size 1.27 1.27)
					(thickness 0.15)
				)
				(justify left bottom)
				(hide yes)
			)
		)
		(property "Author" "Antmicro"
			(at 156.21 73.025 0)
			(effects
				(font
					(size 1.27 1.27)
					(thickness 0.15)
				)
				(justify left bottom)
				(hide yes)
			)
		)
		(property "Val" "100n"
			(at 131.445 92.71 90)
			(effects
				(font
					(size 1.27 1.27)
					(thickness 0.15)
				)
				(justify right)
			)
		)
		(property "Voltage" "50V"
			(at 158.75 73.025 0)
			(effects
				(font
					(size 1.27 1.27)
				)
				(justify left bottom)
				(hide yes)
			)
		)
		(property "Dielectric" "X5R"
			(at 161.29 73.025 0)
			(effects
				(font
					(size 1.27 1.27)
				)
				(justify left bottom)
				(hide yes)
			)
		)
		(pin "1"
		)
		(pin "2"
		)
		(instances
			(project "sodimm-ddr5-tester"
				(path ""
					(reference "C79")
					(unit 1)
				)
			)
		)
	)
	(symbol
		(lib_id "antmicropower:GND")
		(at 55.88 94.615 0)
		(unit 1)
		(exclude_from_sim no)
		(in_bom yes)
		(on_board yes)
		(dnp no)
		(fields_autoplaced yes)
		(property "Reference" "#PWR073"
			(at 55.88 100.965 0)
			(effects
				(font
					(size 1.27 1.27)
				)
				(hide yes)
			)
		)
		(property "Value" "GND"
			(at 58.42 95.885 0)
			(effects
				(font
					(size 1.27 1.27)
					(thickness 0.15)
				)
				(justify left)
			)
		)
		(property "Footprint" ""
			(at 64.77 102.235 0)
			(effects
				(font
					(size 1.27 1.27)
					(thickness 0.15)
				)
				(justify left bottom)
				(hide yes)
			)
		)
		(property "Datasheet" ""
			(at 64.77 107.315 0)
			(effects
				(font
					(size 1.27 1.27)
					(thickness 0.15)
				)
				(justify left bottom)
				(hide yes)
			)
		)
		(property "Description" ""
			(at 64.77 109.855 0)
			(effects
				(font
					(size 1.27 1.27)
				)
				(justify left bottom)
				(hide yes)
			)
		)
		(property "Author" "Antmicro"
			(at 64.77 102.235 0)
			(effects
				(font
					(size 1.27 1.27)
					(thickness 0.15)
				)
				(justify left bottom)
				(hide yes)
			)
		)
		(property "License" "Apache-2.0"
			(at 64.77 104.775 0)
			(effects
				(font
					(size 1.27 1.27)
					(thickness 0.15)
				)
				(justify left bottom)
				(hide yes)
			)
		)
		(pin "1"
		)
		(instances
			(project "sodimm-ddr5-tester"
				(path ""
					(reference "#PWR073")
					(unit 1)
				)
			)
		)
	)
	(symbol
		(lib_id "antmicropower:GND")
		(at 116.205 191.135 0)
		(unit 1)
		(exclude_from_sim no)
		(in_bom yes)
		(on_board yes)
		(dnp no)
		(fields_autoplaced yes)
		(property "Reference" "#PWR0108"
			(at 116.205 197.485 0)
			(effects
				(font
					(size 1.27 1.27)
				)
				(hide yes)
			)
		)
		(property "Value" "GND"
			(at 118.11 192.405 0)
			(effects
				(font
					(size 1.27 1.27)
					(thickness 0.15)
				)
				(justify left)
			)
		)
		(property "Footprint" ""
			(at 125.095 198.755 0)
			(effects
				(font
					(size 1.27 1.27)
					(thickness 0.15)
				)
				(justify left bottom)
				(hide yes)
			)
		)
		(property "Datasheet" ""
			(at 125.095 203.835 0)
			(effects
				(font
					(size 1.27 1.27)
					(thickness 0.15)
				)
				(justify left bottom)
				(hide yes)
			)
		)
		(property "Description" ""
			(at 125.095 206.375 0)
			(effects
				(font
					(size 1.27 1.27)
				)
				(justify left bottom)
				(hide yes)
			)
		)
		(property "Author" "Antmicro"
			(at 125.095 198.755 0)
			(effects
				(font
					(size 1.27 1.27)
					(thickness 0.15)
				)
				(justify left bottom)
				(hide yes)
			)
		)
		(property "License" "Apache-2.0"
			(at 125.095 201.295 0)
			(effects
				(font
					(size 1.27 1.27)
					(thickness 0.15)
				)
				(justify left bottom)
				(hide yes)
			)
		)
		(pin "1"
		)
		(instances
			(project "sodimm-ddr5-tester"
				(path ""
					(reference "#PWR0108")
					(unit 1)
				)
			)
		)
	)
	(symbol
		(lib_id "antmicropower:GND")
		(at 45.72 220.98 0)
		(unit 1)
		(exclude_from_sim no)
		(in_bom yes)
		(on_board yes)
		(dnp no)
		(fields_autoplaced yes)
		(property "Reference" "#PWR070"
			(at 45.72 227.33 0)
			(effects
				(font
					(size 1.27 1.27)
				)
				(hide yes)
			)
		)
		(property "Value" "GND"
			(at 48.26 222.25 0)
			(effects
				(font
					(size 1.27 1.27)
					(thickness 0.15)
				)
				(justify left)
			)
		)
		(property "Footprint" ""
			(at 54.61 228.6 0)
			(effects
				(font
					(size 1.27 1.27)
					(thickness 0.15)
				)
				(justify left bottom)
				(hide yes)
			)
		)
		(property "Datasheet" ""
			(at 54.61 233.68 0)
			(effects
				(font
					(size 1.27 1.27)
					(thickness 0.15)
				)
				(justify left bottom)
				(hide yes)
			)
		)
		(property "Description" ""
			(at 54.61 236.22 0)
			(effects
				(font
					(size 1.27 1.27)
				)
				(justify left bottom)
				(hide yes)
			)
		)
		(property "Author" "Antmicro"
			(at 54.61 228.6 0)
			(effects
				(font
					(size 1.27 1.27)
					(thickness 0.15)
				)
				(justify left bottom)
				(hide yes)
			)
		)
		(property "License" "Apache-2.0"
			(at 54.61 231.14 0)
			(effects
				(font
					(size 1.27 1.27)
					(thickness 0.15)
				)
				(justify left bottom)
				(hide yes)
			)
		)
		(pin "1"
		)
		(instances
			(project "sodimm-ddr5-tester"
				(path ""
					(reference "#PWR070")
					(unit 1)
				)
			)
		)
	)
	(symbol
		(lib_id "antmicropower:GND")
		(at 144.145 162.56 0)
		(unit 1)
		(exclude_from_sim no)
		(in_bom yes)
		(on_board yes)
		(dnp no)
		(fields_autoplaced yes)
		(property "Reference" "#PWR084"
			(at 144.145 168.91 0)
			(effects
				(font
					(size 1.27 1.27)
				)
				(hide yes)
			)
		)
		(property "Value" "GND"
			(at 146.05 163.83 0)
			(effects
				(font
					(size 1.27 1.27)
					(thickness 0.15)
				)
				(justify left)
			)
		)
		(property "Footprint" ""
			(at 153.035 170.18 0)
			(effects
				(font
					(size 1.27 1.27)
					(thickness 0.15)
				)
				(justify left bottom)
				(hide yes)
			)
		)
		(property "Datasheet" ""
			(at 153.035 175.26 0)
			(effects
				(font
					(size 1.27 1.27)
					(thickness 0.15)
				)
				(justify left bottom)
				(hide yes)
			)
		)
		(property "Description" ""
			(at 153.035 177.8 0)
			(effects
				(font
					(size 1.27 1.27)
				)
				(justify left bottom)
				(hide yes)
			)
		)
		(property "Author" "Antmicro"
			(at 153.035 170.18 0)
			(effects
				(font
					(size 1.27 1.27)
					(thickness 0.15)
				)
				(justify left bottom)
				(hide yes)
			)
		)
		(property "License" "Apache-2.0"
			(at 153.035 172.72 0)
			(effects
				(font
					(size 1.27 1.27)
					(thickness 0.15)
				)
				(justify left bottom)
				(hide yes)
			)
		)
		(pin "1"
		)
		(instances
			(project "sodimm-ddr5-tester"
				(path ""
					(reference "#PWR084")
					(unit 1)
				)
			)
		)
	)
	(symbol
		(lib_id "antmicropower:GND")
		(at 38.735 123.825 0)
		(mirror y)
		(unit 1)
		(exclude_from_sim no)
		(in_bom yes)
		(on_board yes)
		(dnp no)
		(fields_autoplaced yes)
		(property "Reference" "#PWR052"
			(at 38.735 130.175 0)
			(effects
				(font
					(size 1.27 1.27)
				)
				(hide yes)
			)
		)
		(property "Value" "GND"
			(at 40.64 125.095 0)
			(effects
				(font
					(size 1.27 1.27)
					(thickness 0.15)
				)
				(justify right)
			)
		)
		(property "Footprint" ""
			(at 29.845 131.445 0)
			(effects
				(font
					(size 1.27 1.27)
					(thickness 0.15)
				)
				(justify left bottom)
				(hide yes)
			)
		)
		(property "Datasheet" ""
			(at 29.845 136.525 0)
			(effects
				(font
					(size 1.27 1.27)
					(thickness 0.15)
				)
				(justify left bottom)
				(hide yes)
			)
		)
		(property "Description" ""
			(at 29.845 139.065 0)
			(effects
				(font
					(size 1.27 1.27)
				)
				(justify left bottom)
				(hide yes)
			)
		)
		(property "Author" "Antmicro"
			(at 29.845 131.445 0)
			(effects
				(font
					(size 1.27 1.27)
					(thickness 0.15)
				)
				(justify left bottom)
				(hide yes)
			)
		)
		(property "License" "Apache-2.0"
			(at 29.845 133.985 0)
			(effects
				(font
					(size 1.27 1.27)
					(thickness 0.15)
				)
				(justify left bottom)
				(hide yes)
			)
		)
		(pin "1"
		)
		(instances
			(project "sodimm-ddr5-tester"
				(path ""
					(reference "#PWR052")
					(unit 1)
				)
			)
		)
	)
	(symbol
		(lib_id "antmicropower:+1V2_MGTAVTT")
		(at 311.15 80.645 0)
		(unit 1)
		(exclude_from_sim no)
		(in_bom yes)
		(on_board yes)
		(dnp no)
		(fields_autoplaced yes)
		(property "Reference" "#PWR0164"
			(at 311.15 84.455 0)
			(effects
				(font
					(size 1.27 1.27)
				)
				(hide yes)
			)
		)
		(property "Value" "+1V2_MGTAVTT"
			(at 311.15 76.835 0)
			(effects
				(font
					(size 1.27 1.27)
				)
			)
		)
		(property "Footprint" ""
			(at 311.15 80.645 0)
			(effects
				(font
					(size 1.27 1.27)
				)
				(hide yes)
			)
		)
		(property "Datasheet" ""
			(at 311.15 80.645 0)
			(effects
				(font
					(size 1.27 1.27)
				)
				(hide yes)
			)
		)
		(property "Description" ""
			(at 311.15 80.645 0)
			(effects
				(font
					(size 1.27 1.27)
				)
			)
		)
		(pin "1"
		)
		(instances
			(project "sodimm-ddr5-tester"
				(path ""
					(reference "#PWR0164")
					(unit 1)
				)
			)
		)
	)
	(symbol
		(lib_id "antmicroCapacitors0402:C_4u7_0402")
		(at 120.65 62.23 270)
		(unit 1)
		(exclude_from_sim no)
		(in_bom yes)
		(on_board yes)
		(dnp no)
		(property "Reference" "C67"
			(at 120.65 62.865 90)
			(effects
				(font
					(size 1.27 1.27)
				)
				(justify left)
			)
		)
		(property "Value" "C_4u7_0402"
			(at 110.49 82.55 0)
			(effects
				(font
					(size 1.27 1.27)
					(thickness 0.15)
				)
				(justify left bottom)
				(hide yes)
			)
		)
		(property "Footprint" "antmicro-footprints:C_0402_1005Metric"
			(at 107.95 82.55 0)
			(effects
				(font
					(size 1.27 1.27)
					(thickness 0.15)
				)
				(justify left bottom)
				(hide yes)
			)
		)
		(property "Datasheet" "https://www.murata.com/products/productdetail?partno=GRM155R61A475MEAA%23"
			(at 105.41 82.55 0)
			(effects
				(font
					(size 1.27 1.27)
					(thickness 0.15)
				)
				(justify left bottom)
				(hide yes)
			)
		)
		(property "Description" ""
			(at 120.65 62.23 0)
			(effects
				(font
					(size 1.27 1.27)
				)
			)
		)
		(property "Manufacturer" "Murata"
			(at 100.33 82.55 0)
			(effects
				(font
					(size 1.27 1.27)
					(thickness 0.15)
				)
				(justify left bottom)
				(hide yes)
			)
		)
		(property "MPN" "GRM155R61A475MEAAD"
			(at 102.87 82.55 0)
			(effects
				(font
					(size 1.27 1.27)
					(thickness 0.15)
				)
				(justify left bottom)
				(hide yes)
			)
		)
		(property "Val" "4u7"
			(at 120.65 66.675 90)
			(effects
				(font
					(size 1.27 1.27)
					(thickness 0.15)
				)
				(justify left)
			)
		)
		(property "License" "Apache-2.0"
			(at 97.79 82.55 0)
			(effects
				(font
					(size 1.27 1.27)
					(thickness 0.15)
				)
				(justify left bottom)
				(hide yes)
			)
		)
		(property "Author" "Antmicro"
			(at 95.25 82.55 0)
			(effects
				(font
					(size 1.27 1.27)
					(thickness 0.15)
				)
				(justify left bottom)
				(hide yes)
			)
		)
		(property "Voltage" ""
			(at 92.71 82.55 0)
			(effects
				(font
					(size 1.27 1.27)
				)
				(justify left bottom)
				(hide yes)
			)
		)
		(property "Dielectric" ""
			(at 90.17 82.55 0)
			(effects
				(font
					(size 1.27 1.27)
				)
				(justify left bottom)
				(hide yes)
			)
		)
		(pin "1"
		)
		(pin "2"
		)
		(instances
			(project "sodimm-ddr5-tester"
				(path ""
					(reference "C67")
					(unit 1)
				)
			)
		)
	)
	(symbol
		(lib_id "antmicroCapacitors0402:C_100n_0402")
		(at 364.49 62.23 90)
		(unit 1)
		(exclude_from_sim no)
		(in_bom yes)
		(on_board yes)
		(dnp no)
		(property "Reference" "C101"
			(at 365.125 57.785 90)
			(effects
				(font
					(size 1.27 1.27)
					(thickness 0.15)
				)
				(justify right)
			)
		)
		(property "Value" "C_100n_0402"
			(at 374.65 41.91 0)
			(effects
				(font
					(size 1.27 1.27)
					(thickness 0.15)
				)
				(justify left bottom)
				(hide yes)
			)
		)
		(property "Footprint" "antmicro-footprints:C_0402_1005Metric"
			(at 377.19 41.91 0)
			(effects
				(font
					(size 1.27 1.27)
					(thickness 0.15)
				)
				(justify left bottom)
				(hide yes)
			)
		)
		(property "Datasheet" "https://www.murata.com/products/productdetail?partno=GRM155R61H104KE14%23"
			(at 379.73 41.91 0)
			(effects
				(font
					(size 1.27 1.27)
					(thickness 0.15)
				)
				(justify left bottom)
				(hide yes)
			)
		)
		(property "Description" ""
			(at 364.49 62.23 0)
			(effects
				(font
					(size 1.27 1.27)
				)
			)
		)
		(property "MPN" "GRM155R61H104KE14D"
			(at 382.27 41.91 0)
			(effects
				(font
					(size 1.27 1.27)
					(thickness 0.15)
				)
				(justify left bottom)
				(hide yes)
			)
		)
		(property "Manufacturer" "Murata"
			(at 384.81 41.91 0)
			(effects
				(font
					(size 1.27 1.27)
					(thickness 0.15)
				)
				(justify left bottom)
				(hide yes)
			)
		)
		(property "License" "Apache-2.0"
			(at 387.35 41.91 0)
			(effects
				(font
					(size 1.27 1.27)
					(thickness 0.15)
				)
				(justify left bottom)
				(hide yes)
			)
		)
		(property "Author" "Antmicro"
			(at 389.89 41.91 0)
			(effects
				(font
					(size 1.27 1.27)
					(thickness 0.15)
				)
				(justify left bottom)
				(hide yes)
			)
		)
		(property "Val" "100n"
			(at 365.125 61.595 90)
			(effects
				(font
					(size 1.27 1.27)
					(thickness 0.15)
				)
				(justify right)
			)
		)
		(property "Voltage" "50V"
			(at 392.43 41.91 0)
			(effects
				(font
					(size 1.27 1.27)
				)
				(justify left bottom)
				(hide yes)
			)
		)
		(property "Dielectric" "X5R"
			(at 394.97 41.91 0)
			(effects
				(font
					(size 1.27 1.27)
				)
				(justify left bottom)
				(hide yes)
			)
		)
		(pin "1"
		)
		(pin "2"
		)
		(instances
			(project "sodimm-ddr5-tester"
				(path ""
					(reference "C101")
					(unit 1)
				)
			)
		)
	)
	(symbol
		(lib_id "antmicropower:+1V0")
		(at 99.695 57.785 0)
		(unit 1)
		(exclude_from_sim no)
		(in_bom yes)
		(on_board yes)
		(dnp no)
		(fields_autoplaced yes)
		(property "Reference" "#PWR0190"
			(at 99.695 61.595 0)
			(effects
				(font
					(size 1.27 1.27)
				)
				(hide yes)
			)
		)
		(property "Value" "+1V0"
			(at 99.695 54.229 0)
			(effects
				(font
					(size 1.27 1.27)
				)
			)
		)
		(property "Footprint" ""
			(at 99.695 57.785 0)
			(effects
				(font
					(size 1.27 1.27)
				)
				(hide yes)
			)
		)
		(property "Datasheet" ""
			(at 99.695 57.785 0)
			(effects
				(font
					(size 1.27 1.27)
				)
				(hide yes)
			)
		)
		(property "Description" ""
			(at 99.695 57.785 0)
			(effects
				(font
					(size 1.27 1.27)
				)
			)
		)
		(pin "1"
		)
		(instances
			(project "sodimm-ddr5-tester"
				(path ""
					(reference "#PWR0190")
					(unit 1)
				)
			)
		)
	)
	(symbol
		(lib_id "antmicropower:GND")
		(at 80.645 190.5 0)
		(unit 1)
		(exclude_from_sim no)
		(in_bom yes)
		(on_board yes)
		(dnp no)
		(fields_autoplaced yes)
		(property "Reference" "#PWR099"
			(at 80.645 196.85 0)
			(effects
				(font
					(size 1.27 1.27)
				)
				(hide yes)
			)
		)
		(property "Value" "GND"
			(at 82.55 191.77 0)
			(effects
				(font
					(size 1.27 1.27)
					(thickness 0.15)
				)
				(justify left)
			)
		)
		(property "Footprint" ""
			(at 89.535 198.12 0)
			(effects
				(font
					(size 1.27 1.27)
					(thickness 0.15)
				)
				(justify left bottom)
				(hide yes)
			)
		)
		(property "Datasheet" ""
			(at 89.535 203.2 0)
			(effects
				(font
					(size 1.27 1.27)
					(thickness 0.15)
				)
				(justify left bottom)
				(hide yes)
			)
		)
		(property "Description" ""
			(at 89.535 205.74 0)
			(effects
				(font
					(size 1.27 1.27)
				)
				(justify left bottom)
				(hide yes)
			)
		)
		(property "Author" "Antmicro"
			(at 89.535 198.12 0)
			(effects
				(font
					(size 1.27 1.27)
					(thickness 0.15)
				)
				(justify left bottom)
				(hide yes)
			)
		)
		(property "License" "Apache-2.0"
			(at 89.535 200.66 0)
			(effects
				(font
					(size 1.27 1.27)
					(thickness 0.15)
				)
				(justify left bottom)
				(hide yes)
			)
		)
		(pin "1"
		)
		(instances
			(project "sodimm-ddr5-tester"
				(path ""
					(reference "#PWR099")
					(unit 1)
				)
			)
		)
	)
	(symbol
		(lib_id "antmicropower:GND")
		(at 331.47 63.5 0)
		(unit 1)
		(exclude_from_sim no)
		(in_bom yes)
		(on_board yes)
		(dnp no)
		(fields_autoplaced yes)
		(property "Reference" "#PWR0158"
			(at 331.47 69.85 0)
			(effects
				(font
					(size 1.27 1.27)
				)
				(hide yes)
			)
		)
		(property "Value" "GND"
			(at 334.01 64.77 0)
			(effects
				(font
					(size 1.27 1.27)
					(thickness 0.15)
				)
				(justify left)
			)
		)
		(property "Footprint" ""
			(at 340.36 71.12 0)
			(effects
				(font
					(size 1.27 1.27)
					(thickness 0.15)
				)
				(justify left bottom)
				(hide yes)
			)
		)
		(property "Datasheet" ""
			(at 340.36 76.2 0)
			(effects
				(font
					(size 1.27 1.27)
					(thickness 0.15)
				)
				(justify left bottom)
				(hide yes)
			)
		)
		(property "Description" ""
			(at 340.36 78.74 0)
			(effects
				(font
					(size 1.27 1.27)
				)
				(justify left bottom)
				(hide yes)
			)
		)
		(property "Author" "Antmicro"
			(at 340.36 71.12 0)
			(effects
				(font
					(size 1.27 1.27)
					(thickness 0.15)
				)
				(justify left bottom)
				(hide yes)
			)
		)
		(property "License" "Apache-2.0"
			(at 340.36 73.66 0)
			(effects
				(font
					(size 1.27 1.27)
					(thickness 0.15)
				)
				(justify left bottom)
				(hide yes)
			)
		)
		(pin "1"
		)
		(instances
			(project "sodimm-ddr5-tester"
				(path ""
					(reference "#PWR0158")
					(unit 1)
				)
			)
		)
	)
	(symbol
		(lib_id "antmicroCapacitors0402:C_100n_0402")
		(at 52.705 219.71 90)
		(unit 1)
		(exclude_from_sim no)
		(in_bom yes)
		(on_board yes)
		(dnp no)
		(property "Reference" "C30"
			(at 53.34 215.265 90)
			(effects
				(font
					(size 1.27 1.27)
					(thickness 0.15)
				)
				(justify right)
			)
		)
		(property "Value" "C_100n_0402"
			(at 62.865 199.39 0)
			(effects
				(font
					(size 1.27 1.27)
					(thickness 0.15)
				)
				(justify left bottom)
				(hide yes)
			)
		)
		(property "Footprint" "antmicro-footprints:C_0402_1005Metric"
			(at 65.405 199.39 0)
			(effects
				(font
					(size 1.27 1.27)
					(thickness 0.15)
				)
				(justify left bottom)
				(hide yes)
			)
		)
		(property "Datasheet" "https://www.murata.com/products/productdetail?partno=GRM155R61H104KE14%23"
			(at 67.945 199.39 0)
			(effects
				(font
					(size 1.27 1.27)
					(thickness 0.15)
				)
				(justify left bottom)
				(hide yes)
			)
		)
		(property "Description" ""
			(at 52.705 219.71 0)
			(effects
				(font
					(size 1.27 1.27)
				)
			)
		)
		(property "MPN" "GRM155R61H104KE14D"
			(at 70.485 199.39 0)
			(effects
				(font
					(size 1.27 1.27)
					(thickness 0.15)
				)
				(justify left bottom)
				(hide yes)
			)
		)
		(property "Manufacturer" "Murata"
			(at 73.025 199.39 0)
			(effects
				(font
					(size 1.27 1.27)
					(thickness 0.15)
				)
				(justify left bottom)
				(hide yes)
			)
		)
		(property "License" "Apache-2.0"
			(at 75.565 199.39 0)
			(effects
				(font
					(size 1.27 1.27)
					(thickness 0.15)
				)
				(justify left bottom)
				(hide yes)
			)
		)
		(property "Author" "Antmicro"
			(at 78.105 199.39 0)
			(effects
				(font
					(size 1.27 1.27)
					(thickness 0.15)
				)
				(justify left bottom)
				(hide yes)
			)
		)
		(property "Val" "100n"
			(at 53.34 219.075 90)
			(effects
				(font
					(size 1.27 1.27)
					(thickness 0.15)
				)
				(justify right)
			)
		)
		(property "Voltage" "50V"
			(at 80.645 199.39 0)
			(effects
				(font
					(size 1.27 1.27)
				)
				(justify left bottom)
				(hide yes)
			)
		)
		(property "Dielectric" "X5R"
			(at 83.185 199.39 0)
			(effects
				(font
					(size 1.27 1.27)
				)
				(justify left bottom)
				(hide yes)
			)
		)
		(pin "1"
		)
		(pin "2"
		)
		(instances
			(project "sodimm-ddr5-tester"
				(path ""
					(reference "C30")
					(unit 1)
				)
			)
		)
	)
	(symbol
		(lib_id "antmicroCapacitors0402:C_100n_0402")
		(at 151.13 160.655 90)
		(unit 1)
		(exclude_from_sim no)
		(in_bom yes)
		(on_board yes)
		(dnp no)
		(property "Reference" "C44"
			(at 151.765 156.21 90)
			(effects
				(font
					(size 1.27 1.27)
					(thickness 0.15)
				)
				(justify right)
			)
		)
		(property "Value" "C_100n_0402"
			(at 161.29 140.335 0)
			(effects
				(font
					(size 1.27 1.27)
					(thickness 0.15)
				)
				(justify left bottom)
				(hide yes)
			)
		)
		(property "Footprint" "antmicro-footprints:C_0402_1005Metric"
			(at 163.83 140.335 0)
			(effects
				(font
					(size 1.27 1.27)
					(thickness 0.15)
				)
				(justify left bottom)
				(hide yes)
			)
		)
		(property "Datasheet" "https://www.murata.com/products/productdetail?partno=GRM155R61H104KE14%23"
			(at 166.37 140.335 0)
			(effects
				(font
					(size 1.27 1.27)
					(thickness 0.15)
				)
				(justify left bottom)
				(hide yes)
			)
		)
		(property "Description" ""
			(at 151.13 160.655 0)
			(effects
				(font
					(size 1.27 1.27)
				)
			)
		)
		(property "MPN" "GRM155R61H104KE14D"
			(at 168.91 140.335 0)
			(effects
				(font
					(size 1.27 1.27)
					(thickness 0.15)
				)
				(justify left bottom)
				(hide yes)
			)
		)
		(property "Manufacturer" "Murata"
			(at 171.45 140.335 0)
			(effects
				(font
					(size 1.27 1.27)
					(thickness 0.15)
				)
				(justify left bottom)
				(hide yes)
			)
		)
		(property "License" "Apache-2.0"
			(at 173.99 140.335 0)
			(effects
				(font
					(size 1.27 1.27)
					(thickness 0.15)
				)
				(justify left bottom)
				(hide yes)
			)
		)
		(property "Author" "Antmicro"
			(at 176.53 140.335 0)
			(effects
				(font
					(size 1.27 1.27)
					(thickness 0.15)
				)
				(justify left bottom)
				(hide yes)
			)
		)
		(property "Val" "100n"
			(at 151.765 160.02 90)
			(effects
				(font
					(size 1.27 1.27)
					(thickness 0.15)
				)
				(justify right)
			)
		)
		(property "Voltage" "50V"
			(at 179.07 140.335 0)
			(effects
				(font
					(size 1.27 1.27)
				)
				(justify left bottom)
				(hide yes)
			)
		)
		(property "Dielectric" "X5R"
			(at 181.61 140.335 0)
			(effects
				(font
					(size 1.27 1.27)
				)
				(justify left bottom)
				(hide yes)
			)
		)
		(pin "1"
		)
		(pin "2"
		)
		(instances
			(project "sodimm-ddr5-tester"
				(path ""
					(reference "C44")
					(unit 1)
				)
			)
		)
	)
	(symbol
		(lib_id "antmicroCapacitors0402:C_4u7_0402")
		(at 73.66 117.475 270)
		(unit 1)
		(exclude_from_sim no)
		(in_bom yes)
		(on_board yes)
		(dnp no)
		(property "Reference" "C43"
			(at 73.66 118.11 90)
			(effects
				(font
					(size 1.27 1.27)
				)
				(justify left)
			)
		)
		(property "Value" "C_4u7_0402"
			(at 63.5 137.795 0)
			(effects
				(font
					(size 1.27 1.27)
					(thickness 0.15)
				)
				(justify left bottom)
				(hide yes)
			)
		)
		(property "Footprint" "antmicro-footprints:C_0402_1005Metric"
			(at 60.96 137.795 0)
			(effects
				(font
					(size 1.27 1.27)
					(thickness 0.15)
				)
				(justify left bottom)
				(hide yes)
			)
		)
		(property "Datasheet" "https://www.murata.com/products/productdetail?partno=GRM155R61A475MEAA%23"
			(at 58.42 137.795 0)
			(effects
				(font
					(size 1.27 1.27)
					(thickness 0.15)
				)
				(justify left bottom)
				(hide yes)
			)
		)
		(property "Description" ""
			(at 73.66 117.475 0)
			(effects
				(font
					(size 1.27 1.27)
				)
			)
		)
		(property "Manufacturer" "Murata"
			(at 53.34 137.795 0)
			(effects
				(font
					(size 1.27 1.27)
					(thickness 0.15)
				)
				(justify left bottom)
				(hide yes)
			)
		)
		(property "MPN" "GRM155R61A475MEAAD"
			(at 55.88 137.795 0)
			(effects
				(font
					(size 1.27 1.27)
					(thickness 0.15)
				)
				(justify left bottom)
				(hide yes)
			)
		)
		(property "Val" "4u7"
			(at 73.66 121.92 90)
			(effects
				(font
					(size 1.27 1.27)
					(thickness 0.15)
				)
				(justify left)
			)
		)
		(property "License" "Apache-2.0"
			(at 50.8 137.795 0)
			(effects
				(font
					(size 1.27 1.27)
					(thickness 0.15)
				)
				(justify left bottom)
				(hide yes)
			)
		)
		(property "Author" "Antmicro"
			(at 48.26 137.795 0)
			(effects
				(font
					(size 1.27 1.27)
					(thickness 0.15)
				)
				(justify left bottom)
				(hide yes)
			)
		)
		(property "Voltage" ""
			(at 45.72 137.795 0)
			(effects
				(font
					(size 1.27 1.27)
				)
				(justify left bottom)
				(hide yes)
			)
		)
		(property "Dielectric" ""
			(at 43.18 137.795 0)
			(effects
				(font
					(size 1.27 1.27)
				)
				(justify left bottom)
				(hide yes)
			)
		)
		(pin "1"
		)
		(pin "2"
		)
		(instances
			(project "sodimm-ddr5-tester"
				(path ""
					(reference "C43")
					(unit 1)
				)
			)
		)
	)
	(symbol
		(lib_id "antmicropower:GND")
		(at 340.995 95.885 0)
		(unit 1)
		(exclude_from_sim no)
		(in_bom yes)
		(on_board yes)
		(dnp no)
		(fields_autoplaced yes)
		(property "Reference" "#PWR0148"
			(at 340.995 102.235 0)
			(effects
				(font
					(size 1.27 1.27)
				)
				(hide yes)
			)
		)
		(property "Value" "GND"
			(at 342.9 97.155 0)
			(effects
				(font
					(size 1.27 1.27)
					(thickness 0.15)
				)
				(justify left)
			)
		)
		(property "Footprint" ""
			(at 349.885 103.505 0)
			(effects
				(font
					(size 1.27 1.27)
					(thickness 0.15)
				)
				(justify left bottom)
				(hide yes)
			)
		)
		(property "Datasheet" ""
			(at 349.885 108.585 0)
			(effects
				(font
					(size 1.27 1.27)
					(thickness 0.15)
				)
				(justify left bottom)
				(hide yes)
			)
		)
		(property "Description" ""
			(at 349.885 111.125 0)
			(effects
				(font
					(size 1.27 1.27)
				)
				(justify left bottom)
				(hide yes)
			)
		)
		(property "Author" "Antmicro"
			(at 349.885 103.505 0)
			(effects
				(font
					(size 1.27 1.27)
					(thickness 0.15)
				)
				(justify left bottom)
				(hide yes)
			)
		)
		(property "License" "Apache-2.0"
			(at 349.885 106.045 0)
			(effects
				(font
					(size 1.27 1.27)
					(thickness 0.15)
				)
				(justify left bottom)
				(hide yes)
			)
		)
		(pin "1"
		)
		(instances
			(project "sodimm-ddr5-tester"
				(path ""
					(reference "#PWR0148")
					(unit 1)
				)
			)
		)
	)
	(symbol
		(lib_id "antmicroCapacitors0603:C_47u_0603")
		(at 38.735 116.84 270)
		(unit 1)
		(exclude_from_sim no)
		(in_bom yes)
		(on_board yes)
		(dnp no)
		(property "Reference" "C11"
			(at 38.735 117.475 90)
			(effects
				(font
					(size 1.27 1.27)
				)
				(justify left)
			)
		)
		(property "Value" "C_47u_0603"
			(at 28.575 137.16 0)
			(effects
				(font
					(size 1.27 1.27)
					(thickness 0.15)
				)
				(justify left bottom)
				(hide yes)
			)
		)
		(property "Footprint" "antmicro-footprints:C_0603_1608Metric"
			(at 26.035 137.16 0)
			(effects
				(font
					(size 1.27 1.27)
					(thickness 0.15)
				)
				(justify left bottom)
				(hide yes)
			)
		)
		(property "Datasheet" "https://www.murata.com/products/productdetail?partno=GRM188R60J476ME15%23"
			(at 23.495 137.16 0)
			(effects
				(font
					(size 1.27 1.27)
					(thickness 0.15)
				)
				(justify left bottom)
				(hide yes)
			)
		)
		(property "Description" ""
			(at 38.735 116.84 0)
			(effects
				(font
					(size 1.27 1.27)
				)
			)
		)
		(property "Manufacturer" "Murata"
			(at 18.415 137.16 0)
			(effects
				(font
					(size 1.27 1.27)
					(thickness 0.15)
				)
				(justify left bottom)
				(hide yes)
			)
		)
		(property "MPN" "GRM188R60J476ME15D"
			(at 20.955 137.16 0)
			(effects
				(font
					(size 1.27 1.27)
					(thickness 0.15)
				)
				(justify left bottom)
				(hide yes)
			)
		)
		(property "Val" "47u"
			(at 38.735 121.285 90)
			(effects
				(font
					(size 1.27 1.27)
					(thickness 0.15)
				)
				(justify left)
			)
		)
		(property "License" "Apache-2.0"
			(at 15.875 137.16 0)
			(effects
				(font
					(size 1.27 1.27)
					(thickness 0.15)
				)
				(justify left bottom)
				(hide yes)
			)
		)
		(property "Author" "Antmicro"
			(at 13.335 137.16 0)
			(effects
				(font
					(size 1.27 1.27)
					(thickness 0.15)
				)
				(justify left bottom)
				(hide yes)
			)
		)
		(property "Voltage" ""
			(at 10.795 137.16 0)
			(effects
				(font
					(size 1.27 1.27)
				)
				(justify left bottom)
				(hide yes)
			)
		)
		(property "Dielectric" ""
			(at 8.255 137.16 0)
			(effects
				(font
					(size 1.27 1.27)
				)
				(justify left bottom)
				(hide yes)
			)
		)
		(pin "1"
		)
		(pin "2"
		)
		(instances
			(project "sodimm-ddr5-tester"
				(path ""
					(reference "C11")
					(unit 1)
				)
			)
		)
	)
	(symbol
		(lib_id "antmicropower:+1V8")
		(at 330.835 86.36 0)
		(unit 1)
		(exclude_from_sim no)
		(in_bom yes)
		(on_board yes)
		(dnp no)
		(fields_autoplaced yes)
		(property "Reference" "#PWR0146"
			(at 330.835 90.17 0)
			(effects
				(font
					(size 1.27 1.27)
				)
				(hide yes)
			)
		)
		(property "Value" "+1V8"
			(at 327.66 83.82 0)
			(effects
				(font
					(size 1.27 1.27)
					(thickness 0.15)
				)
				(justify left bottom)
			)
		)
		(property "Footprint" ""
			(at 346.075 93.98 0)
			(effects
				(font
					(size 1.27 1.27)
					(thickness 0.15)
				)
				(justify left bottom)
				(hide yes)
			)
		)
		(property "Datasheet" ""
			(at 346.075 96.52 0)
			(effects
				(font
					(size 1.27 1.27)
					(thickness 0.15)
				)
				(justify left bottom)
				(hide yes)
			)
		)
		(property "Description" ""
			(at 330.835 86.36 0)
			(effects
				(font
					(size 1.27 1.27)
				)
			)
		)
		(property "Author" "Antmicro"
			(at 346.075 91.44 0)
			(effects
				(font
					(size 1.27 1.27)
					(thickness 0.15)
				)
				(justify left bottom)
				(hide yes)
			)
		)
		(property "License" "Apache-2.0"
			(at 346.075 93.98 0)
			(effects
				(font
					(size 1.27 1.27)
					(thickness 0.15)
				)
				(justify left bottom)
				(hide yes)
			)
		)
		(pin "1"
		)
		(instances
			(project "sodimm-ddr5-tester"
				(path ""
					(reference "#PWR0146")
					(unit 1)
				)
			)
		)
	)
	(symbol
		(lib_id "antmicropower:GND")
		(at 238.76 114.935 0)
		(mirror y)
		(unit 1)
		(exclude_from_sim no)
		(in_bom yes)
		(on_board yes)
		(dnp no)
		(fields_autoplaced yes)
		(property "Reference" "#PWR0153"
			(at 238.76 121.285 0)
			(effects
				(font
					(size 1.27 1.27)
				)
				(hide yes)
			)
		)
		(property "Value" "GND"
			(at 241.3 116.205 0)
			(effects
				(font
					(size 1.27 1.27)
					(thickness 0.15)
				)
				(justify right)
			)
		)
		(property "Footprint" ""
			(at 229.87 122.555 0)
			(effects
				(font
					(size 1.27 1.27)
					(thickness 0.15)
				)
				(justify left bottom)
				(hide yes)
			)
		)
		(property "Datasheet" ""
			(at 229.87 127.635 0)
			(effects
				(font
					(size 1.27 1.27)
					(thickness 0.15)
				)
				(justify left bottom)
				(hide yes)
			)
		)
		(property "Description" ""
			(at 229.87 130.175 0)
			(effects
				(font
					(size 1.27 1.27)
				)
				(justify left bottom)
				(hide yes)
			)
		)
		(property "Author" "Antmicro"
			(at 229.87 122.555 0)
			(effects
				(font
					(size 1.27 1.27)
					(thickness 0.15)
				)
				(justify left bottom)
				(hide yes)
			)
		)
		(property "License" "Apache-2.0"
			(at 229.87 125.095 0)
			(effects
				(font
					(size 1.27 1.27)
					(thickness 0.15)
				)
				(justify left bottom)
				(hide yes)
			)
		)
		(pin "1"
		)
		(instances
			(project "sodimm-ddr5-tester"
				(path ""
					(reference "#PWR0153")
					(unit 1)
				)
			)
		)
	)
	(symbol
		(lib_id "antmicropower:+1V0")
		(at 39.37 59.055 0)
		(unit 1)
		(exclude_from_sim no)
		(in_bom yes)
		(on_board yes)
		(dnp no)
		(fields_autoplaced yes)
		(property "Reference" "#PWR053"
			(at 39.37 62.865 0)
			(effects
				(font
					(size 1.27 1.27)
				)
				(hide yes)
			)
		)
		(property "Value" "+1V0"
			(at 39.37 55.499 0)
			(effects
				(font
					(size 1.27 1.27)
				)
			)
		)
		(property "Footprint" ""
			(at 39.37 59.055 0)
			(effects
				(font
					(size 1.27 1.27)
				)
				(hide yes)
			)
		)
		(property "Datasheet" ""
			(at 39.37 59.055 0)
			(effects
				(font
					(size 1.27 1.27)
				)
				(hide yes)
			)
		)
		(property "Description" ""
			(at 39.37 59.055 0)
			(effects
				(font
					(size 1.27 1.27)
				)
			)
		)
		(pin "1"
		)
		(instances
			(project "sodimm-ddr5-tester"
				(path ""
					(reference "#PWR053")
					(unit 1)
				)
			)
		)
	)
	(symbol
		(lib_id "antmicroCapacitors0402:C_100n_0402")
		(at 116.84 122.555 90)
		(unit 1)
		(exclude_from_sim no)
		(in_bom yes)
		(on_board yes)
		(dnp no)
		(property "Reference" "C72"
			(at 117.475 118.11 90)
			(effects
				(font
					(size 1.27 1.27)
					(thickness 0.15)
				)
				(justify right)
			)
		)
		(property "Value" "C_100n_0402"
			(at 127 102.235 0)
			(effects
				(font
					(size 1.27 1.27)
					(thickness 0.15)
				)
				(justify left bottom)
				(hide yes)
			)
		)
		(property "Footprint" "antmicro-footprints:C_0402_1005Metric"
			(at 129.54 102.235 0)
			(effects
				(font
					(size 1.27 1.27)
					(thickness 0.15)
				)
				(justify left bottom)
				(hide yes)
			)
		)
		(property "Datasheet" "https://www.murata.com/products/productdetail?partno=GRM155R61H104KE14%23"
			(at 132.08 102.235 0)
			(effects
				(font
					(size 1.27 1.27)
					(thickness 0.15)
				)
				(justify left bottom)
				(hide yes)
			)
		)
		(property "Description" ""
			(at 116.84 122.555 0)
			(effects
				(font
					(size 1.27 1.27)
				)
			)
		)
		(property "MPN" "GRM155R61H104KE14D"
			(at 134.62 102.235 0)
			(effects
				(font
					(size 1.27 1.27)
					(thickness 0.15)
				)
				(justify left bottom)
				(hide yes)
			)
		)
		(property "Manufacturer" "Murata"
			(at 137.16 102.235 0)
			(effects
				(font
					(size 1.27 1.27)
					(thickness 0.15)
				)
				(justify left bottom)
				(hide yes)
			)
		)
		(property "License" "Apache-2.0"
			(at 139.7 102.235 0)
			(effects
				(font
					(size 1.27 1.27)
					(thickness 0.15)
				)
				(justify left bottom)
				(hide yes)
			)
		)
		(property "Author" "Antmicro"
			(at 142.24 102.235 0)
			(effects
				(font
					(size 1.27 1.27)
					(thickness 0.15)
				)
				(justify left bottom)
				(hide yes)
			)
		)
		(property "Val" "100n"
			(at 117.475 121.92 90)
			(effects
				(font
					(size 1.27 1.27)
					(thickness 0.15)
				)
				(justify right)
			)
		)
		(property "Voltage" "50V"
			(at 144.78 102.235 0)
			(effects
				(font
					(size 1.27 1.27)
				)
				(justify left bottom)
				(hide yes)
			)
		)
		(property "Dielectric" "X5R"
			(at 147.32 102.235 0)
			(effects
				(font
					(size 1.27 1.27)
				)
				(justify left bottom)
				(hide yes)
			)
		)
		(pin "1"
		)
		(pin "2"
		)
		(instances
			(project "sodimm-ddr5-tester"
				(path ""
					(reference "C72")
					(unit 1)
				)
			)
		)
	)
	(symbol
		(lib_id "antmicroCapacitors0402:C_100n_0402")
		(at 347.98 62.23 90)
		(unit 1)
		(exclude_from_sim no)
		(in_bom yes)
		(on_board yes)
		(dnp no)
		(property "Reference" "C99"
			(at 348.615 57.785 90)
			(effects
				(font
					(size 1.27 1.27)
					(thickness 0.15)
				)
				(justify right)
			)
		)
		(property "Value" "C_100n_0402"
			(at 358.14 41.91 0)
			(effects
				(font
					(size 1.27 1.27)
					(thickness 0.15)
				)
				(justify left bottom)
				(hide yes)
			)
		)
		(property "Footprint" "antmicro-footprints:C_0402_1005Metric"
			(at 360.68 41.91 0)
			(effects
				(font
					(size 1.27 1.27)
					(thickness 0.15)
				)
				(justify left bottom)
				(hide yes)
			)
		)
		(property "Datasheet" "https://www.murata.com/products/productdetail?partno=GRM155R61H104KE14%23"
			(at 363.22 41.91 0)
			(effects
				(font
					(size 1.27 1.27)
					(thickness 0.15)
				)
				(justify left bottom)
				(hide yes)
			)
		)
		(property "Description" ""
			(at 347.98 62.23 0)
			(effects
				(font
					(size 1.27 1.27)
				)
			)
		)
		(property "MPN" "GRM155R61H104KE14D"
			(at 365.76 41.91 0)
			(effects
				(font
					(size 1.27 1.27)
					(thickness 0.15)
				)
				(justify left bottom)
				(hide yes)
			)
		)
		(property "Manufacturer" "Murata"
			(at 368.3 41.91 0)
			(effects
				(font
					(size 1.27 1.27)
					(thickness 0.15)
				)
				(justify left bottom)
				(hide yes)
			)
		)
		(property "License" "Apache-2.0"
			(at 370.84 41.91 0)
			(effects
				(font
					(size 1.27 1.27)
					(thickness 0.15)
				)
				(justify left bottom)
				(hide yes)
			)
		)
		(property "Author" "Antmicro"
			(at 373.38 41.91 0)
			(effects
				(font
					(size 1.27 1.27)
					(thickness 0.15)
				)
				(justify left bottom)
				(hide yes)
			)
		)
		(property "Val" "100n"
			(at 348.615 61.595 90)
			(effects
				(font
					(size 1.27 1.27)
					(thickness 0.15)
				)
				(justify right)
			)
		)
		(property "Voltage" "50V"
			(at 375.92 41.91 0)
			(effects
				(font
					(size 1.27 1.27)
				)
				(justify left bottom)
				(hide yes)
			)
		)
		(property "Dielectric" "X5R"
			(at 378.46 41.91 0)
			(effects
				(font
					(size 1.27 1.27)
				)
				(justify left bottom)
				(hide yes)
			)
		)
		(pin "1"
		)
		(pin "2"
		)
		(instances
			(project "sodimm-ddr5-tester"
				(path ""
					(reference "C99")
					(unit 1)
				)
			)
		)
	)
	(symbol
		(lib_id "antmicropower:GND")
		(at 87.63 220.98 0)
		(unit 1)
		(exclude_from_sim no)
		(in_bom yes)
		(on_board yes)
		(dnp no)
		(fields_autoplaced yes)
		(property "Reference" "#PWR0106"
			(at 87.63 227.33 0)
			(effects
				(font
					(size 1.27 1.27)
				)
				(hide yes)
			)
		)
		(property "Value" "GND"
			(at 90.17 222.25 0)
			(effects
				(font
					(size 1.27 1.27)
					(thickness 0.15)
				)
				(justify left)
			)
		)
		(property "Footprint" ""
			(at 96.52 228.6 0)
			(effects
				(font
					(size 1.27 1.27)
					(thickness 0.15)
				)
				(justify left bottom)
				(hide yes)
			)
		)
		(property "Datasheet" ""
			(at 96.52 233.68 0)
			(effects
				(font
					(size 1.27 1.27)
					(thickness 0.15)
				)
				(justify left bottom)
				(hide yes)
			)
		)
		(property "Description" ""
			(at 96.52 236.22 0)
			(effects
				(font
					(size 1.27 1.27)
				)
				(justify left bottom)
				(hide yes)
			)
		)
		(property "Author" "Antmicro"
			(at 96.52 228.6 0)
			(effects
				(font
					(size 1.27 1.27)
					(thickness 0.15)
				)
				(justify left bottom)
				(hide yes)
			)
		)
		(property "License" "Apache-2.0"
			(at 96.52 231.14 0)
			(effects
				(font
					(size 1.27 1.27)
					(thickness 0.15)
				)
				(justify left bottom)
				(hide yes)
			)
		)
		(pin "1"
		)
		(instances
			(project "sodimm-ddr5-tester"
				(path ""
					(reference "#PWR0106")
					(unit 1)
				)
			)
		)
	)
	(symbol
		(lib_id "antmicroCapacitors0603:C_47u_0603")
		(at 38.735 214.63 270)
		(unit 1)
		(exclude_from_sim no)
		(in_bom yes)
		(on_board yes)
		(dnp no)
		(property "Reference" "C17"
			(at 38.735 215.265 90)
			(effects
				(font
					(size 1.27 1.27)
				)
				(justify left)
			)
		)
		(property "Value" "C_47u_0603"
			(at 28.575 234.95 0)
			(effects
				(font
					(size 1.27 1.27)
					(thickness 0.15)
				)
				(justify left bottom)
				(hide yes)
			)
		)
		(property "Footprint" "antmicro-footprints:C_0603_1608Metric"
			(at 26.035 234.95 0)
			(effects
				(font
					(size 1.27 1.27)
					(thickness 0.15)
				)
				(justify left bottom)
				(hide yes)
			)
		)
		(property "Datasheet" "https://www.murata.com/products/productdetail?partno=GRM188R60J476ME15%23"
			(at 23.495 234.95 0)
			(effects
				(font
					(size 1.27 1.27)
					(thickness 0.15)
				)
				(justify left bottom)
				(hide yes)
			)
		)
		(property "Description" ""
			(at 38.735 214.63 0)
			(effects
				(font
					(size 1.27 1.27)
				)
			)
		)
		(property "Manufacturer" "Murata"
			(at 18.415 234.95 0)
			(effects
				(font
					(size 1.27 1.27)
					(thickness 0.15)
				)
				(justify left bottom)
				(hide yes)
			)
		)
		(property "MPN" "GRM188R60J476ME15D"
			(at 20.955 234.95 0)
			(effects
				(font
					(size 1.27 1.27)
					(thickness 0.15)
				)
				(justify left bottom)
				(hide yes)
			)
		)
		(property "Val" "47u"
			(at 38.735 219.075 90)
			(effects
				(font
					(size 1.27 1.27)
					(thickness 0.15)
				)
				(justify left)
			)
		)
		(property "License" "Apache-2.0"
			(at 15.875 234.95 0)
			(effects
				(font
					(size 1.27 1.27)
					(thickness 0.15)
				)
				(justify left bottom)
				(hide yes)
			)
		)
		(property "Author" "Antmicro"
			(at 13.335 234.95 0)
			(effects
				(font
					(size 1.27 1.27)
					(thickness 0.15)
				)
				(justify left bottom)
				(hide yes)
			)
		)
		(property "Voltage" ""
			(at 10.795 234.95 0)
			(effects
				(font
					(size 1.27 1.27)
				)
				(justify left bottom)
				(hide yes)
			)
		)
		(property "Dielectric" ""
			(at 8.255 234.95 0)
			(effects
				(font
					(size 1.27 1.27)
				)
				(justify left bottom)
				(hide yes)
			)
		)
		(pin "1"
		)
		(pin "2"
		)
		(instances
			(project "sodimm-ddr5-tester"
				(path ""
					(reference "C17")
					(unit 1)
				)
			)
		)
	)
	(symbol
		(lib_id "antmicropower:GND")
		(at 80.01 248.92 0)
		(unit 1)
		(exclude_from_sim no)
		(in_bom yes)
		(on_board yes)
		(dnp no)
		(fields_autoplaced yes)
		(property "Reference" "#PWR098"
			(at 80.01 255.27 0)
			(effects
				(font
					(size 1.27 1.27)
				)
				(hide yes)
			)
		)
		(property "Value" "GND"
			(at 82.55 250.19 0)
			(effects
				(font
					(size 1.27 1.27)
					(thickness 0.15)
				)
				(justify left)
			)
		)
		(property "Footprint" ""
			(at 88.9 256.54 0)
			(effects
				(font
					(size 1.27 1.27)
					(thickness 0.15)
				)
				(justify left bottom)
				(hide yes)
			)
		)
		(property "Datasheet" ""
			(at 88.9 261.62 0)
			(effects
				(font
					(size 1.27 1.27)
					(thickness 0.15)
				)
				(justify left bottom)
				(hide yes)
			)
		)
		(property "Description" ""
			(at 88.9 264.16 0)
			(effects
				(font
					(size 1.27 1.27)
				)
				(justify left bottom)
				(hide yes)
			)
		)
		(property "Author" "Antmicro"
			(at 88.9 256.54 0)
			(effects
				(font
					(size 1.27 1.27)
					(thickness 0.15)
				)
				(justify left bottom)
				(hide yes)
			)
		)
		(property "License" "Apache-2.0"
			(at 88.9 259.08 0)
			(effects
				(font
					(size 1.27 1.27)
					(thickness 0.15)
				)
				(justify left bottom)
				(hide yes)
			)
		)
		(pin "1"
		)
		(instances
			(project "sodimm-ddr5-tester"
				(path ""
					(reference "#PWR098")
					(unit 1)
				)
			)
		)
	)
	(symbol
		(lib_id "antmicropower:+1V8")
		(at 208.28 81.28 0)
		(unit 1)
		(exclude_from_sim no)
		(in_bom yes)
		(on_board yes)
		(dnp no)
		(fields_autoplaced yes)
		(property "Reference" "#PWR0149"
			(at 208.28 85.09 0)
			(effects
				(font
					(size 1.27 1.27)
				)
				(hide yes)
			)
		)
		(property "Value" "+1V8"
			(at 205.105 78.74 0)
			(effects
				(font
					(size 1.27 1.27)
					(thickness 0.15)
				)
				(justify left bottom)
			)
		)
		(property "Footprint" ""
			(at 223.52 88.9 0)
			(effects
				(font
					(size 1.27 1.27)
					(thickness 0.15)
				)
				(justify left bottom)
				(hide yes)
			)
		)
		(property "Datasheet" ""
			(at 223.52 91.44 0)
			(effects
				(font
					(size 1.27 1.27)
					(thickness 0.15)
				)
				(justify left bottom)
				(hide yes)
			)
		)
		(property "Description" ""
			(at 208.28 81.28 0)
			(effects
				(font
					(size 1.27 1.27)
				)
			)
		)
		(property "Author" "Antmicro"
			(at 223.52 86.36 0)
			(effects
				(font
					(size 1.27 1.27)
					(thickness 0.15)
				)
				(justify left bottom)
				(hide yes)
			)
		)
		(property "License" "Apache-2.0"
			(at 223.52 88.9 0)
			(effects
				(font
					(size 1.27 1.27)
					(thickness 0.15)
				)
				(justify left bottom)
				(hide yes)
			)
		)
		(pin "1"
		)
		(instances
			(project "sodimm-ddr5-tester"
				(path ""
					(reference "#PWR0149")
					(unit 1)
				)
			)
		)
	)
	(symbol
		(lib_id "antmicropower:GND")
		(at 139.065 94.615 0)
		(unit 1)
		(exclude_from_sim no)
		(in_bom yes)
		(on_board yes)
		(dnp no)
		(fields_autoplaced yes)
		(property "Reference" "#PWR0132"
			(at 139.065 100.965 0)
			(effects
				(font
					(size 1.27 1.27)
				)
				(hide yes)
			)
		)
		(property "Value" "GND"
			(at 140.97 95.885 0)
			(effects
				(font
					(size 1.27 1.27)
					(thickness 0.15)
				)
				(justify left)
			)
		)
		(property "Footprint" ""
			(at 147.955 102.235 0)
			(effects
				(font
					(size 1.27 1.27)
					(thickness 0.15)
				)
				(justify left bottom)
				(hide yes)
			)
		)
		(property "Datasheet" ""
			(at 147.955 107.315 0)
			(effects
				(font
					(size 1.27 1.27)
					(thickness 0.15)
				)
				(justify left bottom)
				(hide yes)
			)
		)
		(property "Description" ""
			(at 147.955 109.855 0)
			(effects
				(font
					(size 1.27 1.27)
				)
				(justify left bottom)
				(hide yes)
			)
		)
		(property "Author" "Antmicro"
			(at 147.955 102.235 0)
			(effects
				(font
					(size 1.27 1.27)
					(thickness 0.15)
				)
				(justify left bottom)
				(hide yes)
			)
		)
		(property "License" "Apache-2.0"
			(at 147.955 104.775 0)
			(effects
				(font
					(size 1.27 1.27)
					(thickness 0.15)
				)
				(justify left bottom)
				(hide yes)
			)
		)
		(pin "1"
		)
		(instances
			(project "sodimm-ddr5-tester"
				(path ""
					(reference "#PWR0132")
					(unit 1)
				)
			)
		)
	)
	(symbol
		(lib_id "antmicropower:GND")
		(at 114.3 94.615 0)
		(unit 1)
		(exclude_from_sim no)
		(in_bom yes)
		(on_board yes)
		(dnp no)
		(fields_autoplaced yes)
		(property "Reference" "#PWR0118"
			(at 114.3 100.965 0)
			(effects
				(font
					(size 1.27 1.27)
				)
				(hide yes)
			)
		)
		(property "Value" "GND"
			(at 116.84 95.885 0)
			(effects
				(font
					(size 1.27 1.27)
					(thickness 0.15)
				)
				(justify left)
			)
		)
		(property "Footprint" ""
			(at 123.19 102.235 0)
			(effects
				(font
					(size 1.27 1.27)
					(thickness 0.15)
				)
				(justify left bottom)
				(hide yes)
			)
		)
		(property "Datasheet" ""
			(at 123.19 107.315 0)
			(effects
				(font
					(size 1.27 1.27)
					(thickness 0.15)
				)
				(justify left bottom)
				(hide yes)
			)
		)
		(property "Description" ""
			(at 123.19 109.855 0)
			(effects
				(font
					(size 1.27 1.27)
				)
				(justify left bottom)
				(hide yes)
			)
		)
		(property "Author" "Antmicro"
			(at 123.19 102.235 0)
			(effects
				(font
					(size 1.27 1.27)
					(thickness 0.15)
				)
				(justify left bottom)
				(hide yes)
			)
		)
		(property "License" "Apache-2.0"
			(at 123.19 104.775 0)
			(effects
				(font
					(size 1.27 1.27)
					(thickness 0.15)
				)
				(justify left bottom)
				(hide yes)
			)
		)
		(pin "1"
		)
		(instances
			(project "sodimm-ddr5-tester"
				(path ""
					(reference "#PWR0118")
					(unit 1)
				)
			)
		)
	)
	(symbol
		(lib_id "antmicropower:GND")
		(at 347.98 63.5 0)
		(unit 1)
		(exclude_from_sim no)
		(in_bom yes)
		(on_board yes)
		(dnp no)
		(fields_autoplaced yes)
		(property "Reference" "#PWR0155"
			(at 347.98 69.85 0)
			(effects
				(font
					(size 1.27 1.27)
				)
				(hide yes)
			)
		)
		(property "Value" "GND"
			(at 350.52 64.77 0)
			(effects
				(font
					(size 1.27 1.27)
					(thickness 0.15)
				)
				(justify left)
			)
		)
		(property "Footprint" ""
			(at 356.87 71.12 0)
			(effects
				(font
					(size 1.27 1.27)
					(thickness 0.15)
				)
				(justify left bottom)
				(hide yes)
			)
		)
		(property "Datasheet" ""
			(at 356.87 76.2 0)
			(effects
				(font
					(size 1.27 1.27)
					(thickness 0.15)
				)
				(justify left bottom)
				(hide yes)
			)
		)
		(property "Description" ""
			(at 356.87 78.74 0)
			(effects
				(font
					(size 1.27 1.27)
				)
				(justify left bottom)
				(hide yes)
			)
		)
		(property "Author" "Antmicro"
			(at 356.87 71.12 0)
			(effects
				(font
					(size 1.27 1.27)
					(thickness 0.15)
				)
				(justify left bottom)
				(hide yes)
			)
		)
		(property "License" "Apache-2.0"
			(at 356.87 73.66 0)
			(effects
				(font
					(size 1.27 1.27)
					(thickness 0.15)
				)
				(justify left bottom)
				(hide yes)
			)
		)
		(pin "1"
		)
		(instances
			(project "sodimm-ddr5-tester"
				(path ""
					(reference "#PWR0155")
					(unit 1)
				)
			)
		)
	)
	(symbol
		(lib_id "antmicropower:+3V3")
		(at 38.735 211.455 0)
		(unit 1)
		(exclude_from_sim no)
		(in_bom yes)
		(on_board yes)
		(dnp no)
		(fields_autoplaced yes)
		(property "Reference" "#PWR063"
			(at 38.735 215.265 0)
			(effects
				(font
					(size 1.27 1.27)
				)
				(hide yes)
			)
		)
		(property "Value" "+3V3"
			(at 35.56 208.915 0)
			(effects
				(font
					(size 1.27 1.27)
					(thickness 0.15)
				)
				(justify left bottom)
			)
		)
		(property "Footprint" ""
			(at 53.975 219.075 0)
			(effects
				(font
					(size 1.27 1.27)
					(thickness 0.15)
				)
				(justify left bottom)
				(hide yes)
			)
		)
		(property "Datasheet" ""
			(at 53.975 221.615 0)
			(effects
				(font
					(size 1.27 1.27)
					(thickness 0.15)
				)
				(justify left bottom)
				(hide yes)
			)
		)
		(property "Description" ""
			(at 38.735 211.455 0)
			(effects
				(font
					(size 1.27 1.27)
				)
			)
		)
		(property "Author" "Antmicro"
			(at 53.975 213.995 0)
			(effects
				(font
					(size 1.27 1.27)
					(thickness 0.15)
				)
				(justify left bottom)
				(hide yes)
			)
		)
		(property "License" "Apache-2.0"
			(at 53.975 216.535 0)
			(effects
				(font
					(size 1.27 1.27)
					(thickness 0.15)
				)
				(justify left bottom)
				(hide yes)
			)
		)
		(pin "1"
		)
		(instances
			(project "sodimm-ddr5-tester"
				(path ""
					(reference "#PWR063")
					(unit 1)
				)
			)
		)
	)
	(symbol
		(lib_id "antmicroCapacitors0402:C_100n_0402")
		(at 330.835 94.615 90)
		(unit 1)
		(exclude_from_sim no)
		(in_bom yes)
		(on_board yes)
		(dnp no)
		(property "Reference" "C96"
			(at 331.47 90.17 90)
			(effects
				(font
					(size 1.27 1.27)
					(thickness 0.15)
				)
				(justify right)
			)
		)
		(property "Value" "C_100n_0402"
			(at 340.995 74.295 0)
			(effects
				(font
					(size 1.27 1.27)
					(thickness 0.15)
				)
				(justify left bottom)
				(hide yes)
			)
		)
		(property "Footprint" "antmicro-footprints:C_0402_1005Metric"
			(at 343.535 74.295 0)
			(effects
				(font
					(size 1.27 1.27)
					(thickness 0.15)
				)
				(justify left bottom)
				(hide yes)
			)
		)
		(property "Datasheet" "https://www.murata.com/products/productdetail?partno=GRM155R61H104KE14%23"
			(at 346.075 74.295 0)
			(effects
				(font
					(size 1.27 1.27)
					(thickness 0.15)
				)
				(justify left bottom)
				(hide yes)
			)
		)
		(property "Description" ""
			(at 330.835 94.615 0)
			(effects
				(font
					(size 1.27 1.27)
				)
			)
		)
		(property "MPN" "GRM155R61H104KE14D"
			(at 348.615 74.295 0)
			(effects
				(font
					(size 1.27 1.27)
					(thickness 0.15)
				)
				(justify left bottom)
				(hide yes)
			)
		)
		(property "Manufacturer" "Murata"
			(at 351.155 74.295 0)
			(effects
				(font
					(size 1.27 1.27)
					(thickness 0.15)
				)
				(justify left bottom)
				(hide yes)
			)
		)
		(property "License" "Apache-2.0"
			(at 353.695 74.295 0)
			(effects
				(font
					(size 1.27 1.27)
					(thickness 0.15)
				)
				(justify left bottom)
				(hide yes)
			)
		)
		(property "Author" "Antmicro"
			(at 356.235 74.295 0)
			(effects
				(font
					(size 1.27 1.27)
					(thickness 0.15)
				)
				(justify left bottom)
				(hide yes)
			)
		)
		(property "Val" "100n"
			(at 331.47 93.98 90)
			(effects
				(font
					(size 1.27 1.27)
					(thickness 0.15)
				)
				(justify right)
			)
		)
		(property "Voltage" "50V"
			(at 358.775 74.295 0)
			(effects
				(font
					(size 1.27 1.27)
				)
				(justify left bottom)
				(hide yes)
			)
		)
		(property "Dielectric" "X5R"
			(at 361.315 74.295 0)
			(effects
				(font
					(size 1.27 1.27)
				)
				(justify left bottom)
				(hide yes)
			)
		)
		(pin "1"
		)
		(pin "2"
		)
		(instances
			(project "sodimm-ddr5-tester"
				(path ""
					(reference "C96")
					(unit 1)
				)
			)
		)
	)
	(symbol
		(lib_id "antmicropower:GND")
		(at 89.535 94.615 0)
		(unit 1)
		(exclude_from_sim no)
		(in_bom yes)
		(on_board yes)
		(dnp no)
		(fields_autoplaced yes)
		(property "Reference" "#PWR0102"
			(at 89.535 100.965 0)
			(effects
				(font
					(size 1.27 1.27)
				)
				(hide yes)
			)
		)
		(property "Value" "GND"
			(at 91.44 95.885 0)
			(effects
				(font
					(size 1.27 1.27)
					(thickness 0.15)
				)
				(justify left)
			)
		)
		(property "Footprint" ""
			(at 98.425 102.235 0)
			(effects
				(font
					(size 1.27 1.27)
					(thickness 0.15)
				)
				(justify left bottom)
				(hide yes)
			)
		)
		(property "Datasheet" ""
			(at 98.425 107.315 0)
			(effects
				(font
					(size 1.27 1.27)
					(thickness 0.15)
				)
				(justify left bottom)
				(hide yes)
			)
		)
		(property "Description" ""
			(at 98.425 109.855 0)
			(effects
				(font
					(size 1.27 1.27)
				)
				(justify left bottom)
				(hide yes)
			)
		)
		(property "Author" "Antmicro"
			(at 98.425 102.235 0)
			(effects
				(font
					(size 1.27 1.27)
					(thickness 0.15)
				)
				(justify left bottom)
				(hide yes)
			)
		)
		(property "License" "Apache-2.0"
			(at 98.425 104.775 0)
			(effects
				(font
					(size 1.27 1.27)
					(thickness 0.15)
				)
				(justify left bottom)
				(hide yes)
			)
		)
		(pin "1"
		)
		(instances
			(project "sodimm-ddr5-tester"
				(path ""
					(reference "#PWR0102")
					(unit 1)
				)
			)
		)
	)
	(symbol
		(lib_id "antmicropower:GND")
		(at 73.025 248.92 0)
		(unit 1)
		(exclude_from_sim no)
		(in_bom yes)
		(on_board yes)
		(dnp no)
		(fields_autoplaced yes)
		(property "Reference" "#PWR092"
			(at 73.025 255.27 0)
			(effects
				(font
					(size 1.27 1.27)
				)
				(hide yes)
			)
		)
		(property "Value" "GND"
			(at 74.93 250.19 0)
			(effects
				(font
					(size 1.27 1.27)
					(thickness 0.15)
				)
				(justify left)
			)
		)
		(property "Footprint" ""
			(at 81.915 256.54 0)
			(effects
				(font
					(size 1.27 1.27)
					(thickness 0.15)
				)
				(justify left bottom)
				(hide yes)
			)
		)
		(property "Datasheet" ""
			(at 81.915 261.62 0)
			(effects
				(font
					(size 1.27 1.27)
					(thickness 0.15)
				)
				(justify left bottom)
				(hide yes)
			)
		)
		(property "Description" ""
			(at 81.915 264.16 0)
			(effects
				(font
					(size 1.27 1.27)
				)
				(justify left bottom)
				(hide yes)
			)
		)
		(property "Author" "Antmicro"
			(at 81.915 256.54 0)
			(effects
				(font
					(size 1.27 1.27)
					(thickness 0.15)
				)
				(justify left bottom)
				(hide yes)
			)
		)
		(property "License" "Apache-2.0"
			(at 81.915 259.08 0)
			(effects
				(font
					(size 1.27 1.27)
					(thickness 0.15)
				)
				(justify left bottom)
				(hide yes)
			)
		)
		(pin "1"
		)
		(instances
			(project "sodimm-ddr5-tester"
				(path ""
					(reference "#PWR092")
					(unit 1)
				)
			)
		)
	)
	(symbol
		(lib_id "antmicropower:+1V0")
		(at 215.265 81.28 0)
		(unit 1)
		(exclude_from_sim no)
		(in_bom yes)
		(on_board yes)
		(dnp no)
		(fields_autoplaced yes)
		(property "Reference" "#PWR0150"
			(at 215.265 85.09 0)
			(effects
				(font
					(size 1.27 1.27)
				)
				(hide yes)
			)
		)
		(property "Value" "+1V0"
			(at 215.265 77.724 0)
			(effects
				(font
					(size 1.27 1.27)
				)
			)
		)
		(property "Footprint" ""
			(at 215.265 81.28 0)
			(effects
				(font
					(size 1.27 1.27)
				)
				(hide yes)
			)
		)
		(property "Datasheet" ""
			(at 215.265 81.28 0)
			(effects
				(font
					(size 1.27 1.27)
				)
				(hide yes)
			)
		)
		(property "Description" ""
			(at 215.265 81.28 0)
			(effects
				(font
					(size 1.27 1.27)
				)
			)
		)
		(pin "1"
		)
		(instances
			(project "sodimm-ddr5-tester"
				(path ""
					(reference "#PWR0150")
					(unit 1)
				)
			)
		)
	)
	(symbol
		(lib_id "antmicropower:GND")
		(at 352.425 127 0)
		(unit 1)
		(exclude_from_sim no)
		(in_bom yes)
		(on_board yes)
		(dnp no)
		(fields_autoplaced yes)
		(property "Reference" "#PWR0166"
			(at 352.425 133.35 0)
			(effects
				(font
					(size 1.27 1.27)
				)
				(hide yes)
			)
		)
		(property "Value" "GND"
			(at 354.33 128.27 0)
			(effects
				(font
					(size 1.27 1.27)
					(thickness 0.15)
				)
				(justify left)
			)
		)
		(property "Footprint" ""
			(at 361.315 134.62 0)
			(effects
				(font
					(size 1.27 1.27)
					(thickness 0.15)
				)
				(justify left bottom)
				(hide yes)
			)
		)
		(property "Datasheet" ""
			(at 361.315 139.7 0)
			(effects
				(font
					(size 1.27 1.27)
					(thickness 0.15)
				)
				(justify left bottom)
				(hide yes)
			)
		)
		(property "Description" ""
			(at 361.315 142.24 0)
			(effects
				(font
					(size 1.27 1.27)
				)
				(justify left bottom)
				(hide yes)
			)
		)
		(property "Author" "Antmicro"
			(at 361.315 134.62 0)
			(effects
				(font
					(size 1.27 1.27)
					(thickness 0.15)
				)
				(justify left bottom)
				(hide yes)
			)
		)
		(property "License" "Apache-2.0"
			(at 361.315 137.16 0)
			(effects
				(font
					(size 1.27 1.27)
					(thickness 0.15)
				)
				(justify left bottom)
				(hide yes)
			)
		)
		(pin "1"
		)
		(instances
			(project "sodimm-ddr5-tester"
				(path ""
					(reference "#PWR0166")
					(unit 1)
				)
			)
		)
	)
	(symbol
		(lib_id "antmicropower:GND")
		(at 99.695 67.945 0)
		(mirror y)
		(unit 1)
		(exclude_from_sim no)
		(in_bom yes)
		(on_board yes)
		(dnp no)
		(fields_autoplaced yes)
		(property "Reference" "#PWR0101"
			(at 99.695 74.295 0)
			(effects
				(font
					(size 1.27 1.27)
				)
				(hide yes)
			)
		)
		(property "Value" "GND"
			(at 101.6 69.215 0)
			(effects
				(font
					(size 1.27 1.27)
					(thickness 0.15)
				)
				(justify right)
			)
		)
		(property "Footprint" ""
			(at 90.805 75.565 0)
			(effects
				(font
					(size 1.27 1.27)
					(thickness 0.15)
				)
				(justify left bottom)
				(hide yes)
			)
		)
		(property "Datasheet" ""
			(at 90.805 80.645 0)
			(effects
				(font
					(size 1.27 1.27)
					(thickness 0.15)
				)
				(justify left bottom)
				(hide yes)
			)
		)
		(property "Description" ""
			(at 90.805 83.185 0)
			(effects
				(font
					(size 1.27 1.27)
				)
				(justify left bottom)
				(hide yes)
			)
		)
		(property "Author" "Antmicro"
			(at 90.805 75.565 0)
			(effects
				(font
					(size 1.27 1.27)
					(thickness 0.15)
				)
				(justify left bottom)
				(hide yes)
			)
		)
		(property "License" "Apache-2.0"
			(at 90.805 78.105 0)
			(effects
				(font
					(size 1.27 1.27)
					(thickness 0.15)
				)
				(justify left bottom)
				(hide yes)
			)
		)
		(pin "1"
		)
		(instances
			(project "sodimm-ddr5-tester"
				(path ""
					(reference "#PWR0101")
					(unit 1)
				)
			)
		)
	)
	(symbol
		(lib_id "antmicropower:GND")
		(at 86.995 248.92 0)
		(unit 1)
		(exclude_from_sim no)
		(in_bom yes)
		(on_board yes)
		(dnp no)
		(fields_autoplaced yes)
		(property "Reference" "#PWR0103"
			(at 86.995 255.27 0)
			(effects
				(font
					(size 1.27 1.27)
				)
				(hide yes)
			)
		)
		(property "Value" "GND"
			(at 88.9 250.19 0)
			(effects
				(font
					(size 1.27 1.27)
					(thickness 0.15)
				)
				(justify left)
			)
		)
		(property "Footprint" ""
			(at 95.885 256.54 0)
			(effects
				(font
					(size 1.27 1.27)
					(thickness 0.15)
				)
				(justify left bottom)
				(hide yes)
			)
		)
		(property "Datasheet" ""
			(at 95.885 261.62 0)
			(effects
				(font
					(size 1.27 1.27)
					(thickness 0.15)
				)
				(justify left bottom)
				(hide yes)
			)
		)
		(property "Description" ""
			(at 95.885 264.16 0)
			(effects
				(font
					(size 1.27 1.27)
				)
				(justify left bottom)
				(hide yes)
			)
		)
		(property "Author" "Antmicro"
			(at 95.885 256.54 0)
			(effects
				(font
					(size 1.27 1.27)
					(thickness 0.15)
				)
				(justify left bottom)
				(hide yes)
			)
		)
		(property "License" "Apache-2.0"
			(at 95.885 259.08 0)
			(effects
				(font
					(size 1.27 1.27)
					(thickness 0.15)
				)
				(justify left bottom)
				(hide yes)
			)
		)
		(pin "1"
		)
		(instances
			(project "sodimm-ddr5-tester"
				(path ""
					(reference "#PWR0103")
					(unit 1)
				)
			)
		)
	)
	(symbol
		(lib_id "antmicropower:GND")
		(at 100.33 124.46 0)
		(unit 1)
		(exclude_from_sim no)
		(in_bom yes)
		(on_board yes)
		(dnp no)
		(fields_autoplaced yes)
		(property "Reference" "#PWR0112"
			(at 100.33 130.81 0)
			(effects
				(font
					(size 1.27 1.27)
				)
				(hide yes)
			)
		)
		(property "Value" "GND"
			(at 102.87 125.73 0)
			(effects
				(font
					(size 1.27 1.27)
					(thickness 0.15)
				)
				(justify left)
			)
		)
		(property "Footprint" ""
			(at 109.22 132.08 0)
			(effects
				(font
					(size 1.27 1.27)
					(thickness 0.15)
				)
				(justify left bottom)
				(hide yes)
			)
		)
		(property "Datasheet" ""
			(at 109.22 137.16 0)
			(effects
				(font
					(size 1.27 1.27)
					(thickness 0.15)
				)
				(justify left bottom)
				(hide yes)
			)
		)
		(property "Description" ""
			(at 109.22 139.7 0)
			(effects
				(font
					(size 1.27 1.27)
				)
				(justify left bottom)
				(hide yes)
			)
		)
		(property "Author" "Antmicro"
			(at 109.22 132.08 0)
			(effects
				(font
					(size 1.27 1.27)
					(thickness 0.15)
				)
				(justify left bottom)
				(hide yes)
			)
		)
		(property "License" "Apache-2.0"
			(at 109.22 134.62 0)
			(effects
				(font
					(size 1.27 1.27)
					(thickness 0.15)
				)
				(justify left bottom)
				(hide yes)
			)
		)
		(pin "1"
		)
		(instances
			(project "sodimm-ddr5-tester"
				(path ""
					(reference "#PWR0112")
					(unit 1)
				)
			)
		)
	)
	(symbol
		(lib_id "antmicropower:GND")
		(at 151.13 191.135 0)
		(unit 1)
		(exclude_from_sim no)
		(in_bom yes)
		(on_board yes)
		(dnp no)
		(fields_autoplaced yes)
		(property "Reference" "#PWR0127"
			(at 151.13 197.485 0)
			(effects
				(font
					(size 1.27 1.27)
				)
				(hide yes)
			)
		)
		(property "Value" "GND"
			(at 153.67 192.405 0)
			(effects
				(font
					(size 1.27 1.27)
					(thickness 0.15)
				)
				(justify left)
			)
		)
		(property "Footprint" ""
			(at 160.02 198.755 0)
			(effects
				(font
					(size 1.27 1.27)
					(thickness 0.15)
				)
				(justify left bottom)
				(hide yes)
			)
		)
		(property "Datasheet" ""
			(at 160.02 203.835 0)
			(effects
				(font
					(size 1.27 1.27)
					(thickness 0.15)
				)
				(justify left bottom)
				(hide yes)
			)
		)
		(property "Description" ""
			(at 160.02 206.375 0)
			(effects
				(font
					(size 1.27 1.27)
				)
				(justify left bottom)
				(hide yes)
			)
		)
		(property "Author" "Antmicro"
			(at 160.02 198.755 0)
			(effects
				(font
					(size 1.27 1.27)
					(thickness 0.15)
				)
				(justify left bottom)
				(hide yes)
			)
		)
		(property "License" "Apache-2.0"
			(at 160.02 201.295 0)
			(effects
				(font
					(size 1.27 1.27)
					(thickness 0.15)
				)
				(justify left bottom)
				(hide yes)
			)
		)
		(pin "1"
		)
		(instances
			(project "sodimm-ddr5-tester"
				(path ""
					(reference "#PWR0127")
					(unit 1)
				)
			)
		)
	)
	(symbol
		(lib_id "antmicropower:GND")
		(at 52.07 248.92 0)
		(unit 1)
		(exclude_from_sim no)
		(in_bom yes)
		(on_board yes)
		(dnp no)
		(fields_autoplaced yes)
		(property "Reference" "#PWR075"
			(at 52.07 255.27 0)
			(effects
				(font
					(size 1.27 1.27)
				)
				(hide yes)
			)
		)
		(property "Value" "GND"
			(at 54.61 250.19 0)
			(effects
				(font
					(size 1.27 1.27)
					(thickness 0.15)
				)
				(justify left)
			)
		)
		(property "Footprint" ""
			(at 60.96 256.54 0)
			(effects
				(font
					(size 1.27 1.27)
					(thickness 0.15)
				)
				(justify left bottom)
				(hide yes)
			)
		)
		(property "Datasheet" ""
			(at 60.96 261.62 0)
			(effects
				(font
					(size 1.27 1.27)
					(thickness 0.15)
				)
				(justify left bottom)
				(hide yes)
			)
		)
		(property "Description" ""
			(at 60.96 264.16 0)
			(effects
				(font
					(size 1.27 1.27)
				)
				(justify left bottom)
				(hide yes)
			)
		)
		(property "Author" "Antmicro"
			(at 60.96 256.54 0)
			(effects
				(font
					(size 1.27 1.27)
					(thickness 0.15)
				)
				(justify left bottom)
				(hide yes)
			)
		)
		(property "License" "Apache-2.0"
			(at 60.96 259.08 0)
			(effects
				(font
					(size 1.27 1.27)
					(thickness 0.15)
				)
				(justify left bottom)
				(hide yes)
			)
		)
		(pin "1"
		)
		(instances
			(project "sodimm-ddr5-tester"
				(path ""
					(reference "#PWR075")
					(unit 1)
				)
			)
		)
	)
	(symbol
		(lib_id "antmicroCapacitors0402:C_100n_0402")
		(at 172.085 93.345 90)
		(unit 1)
		(exclude_from_sim no)
		(in_bom yes)
		(on_board yes)
		(dnp no)
		(property "Reference" "C92"
			(at 172.72 88.9 90)
			(effects
				(font
					(size 1.27 1.27)
					(thickness 0.15)
				)
				(justify right)
			)
		)
		(property "Value" "C_100n_0402"
			(at 182.245 73.025 0)
			(effects
				(font
					(size 1.27 1.27)
					(thickness 0.15)
				)
				(justify left bottom)
				(hide yes)
			)
		)
		(property "Footprint" "antmicro-footprints:C_0402_1005Metric"
			(at 184.785 73.025 0)
			(effects
				(font
					(size 1.27 1.27)
					(thickness 0.15)
				)
				(justify left bottom)
				(hide yes)
			)
		)
		(property "Datasheet" "https://www.murata.com/products/productdetail?partno=GRM155R61H104KE14%23"
			(at 187.325 73.025 0)
			(effects
				(font
					(size 1.27 1.27)
					(thickness 0.15)
				)
				(justify left bottom)
				(hide yes)
			)
		)
		(property "Description" ""
			(at 172.085 93.345 0)
			(effects
				(font
					(size 1.27 1.27)
				)
			)
		)
		(property "MPN" "GRM155R61H104KE14D"
			(at 189.865 73.025 0)
			(effects
				(font
					(size 1.27 1.27)
					(thickness 0.15)
				)
				(justify left bottom)
				(hide yes)
			)
		)
		(property "Manufacturer" "Murata"
			(at 192.405 73.025 0)
			(effects
				(font
					(size 1.27 1.27)
					(thickness 0.15)
				)
				(justify left bottom)
				(hide yes)
			)
		)
		(property "License" "Apache-2.0"
			(at 194.945 73.025 0)
			(effects
				(font
					(size 1.27 1.27)
					(thickness 0.15)
				)
				(justify left bottom)
				(hide yes)
			)
		)
		(property "Author" "Antmicro"
			(at 197.485 73.025 0)
			(effects
				(font
					(size 1.27 1.27)
					(thickness 0.15)
				)
				(justify left bottom)
				(hide yes)
			)
		)
		(property "Val" "100n"
			(at 172.72 92.71 90)
			(effects
				(font
					(size 1.27 1.27)
					(thickness 0.15)
				)
				(justify right)
			)
		)
		(property "Voltage" "50V"
			(at 200.025 73.025 0)
			(effects
				(font
					(size 1.27 1.27)
				)
				(justify left bottom)
				(hide yes)
			)
		)
		(property "Dielectric" "X5R"
			(at 202.565 73.025 0)
			(effects
				(font
					(size 1.27 1.27)
				)
				(justify left bottom)
				(hide yes)
			)
		)
		(pin "1"
		)
		(pin "2"
		)
		(instances
			(project "sodimm-ddr5-tester"
				(path ""
					(reference "C92")
					(unit 1)
				)
			)
		)
	)
	(symbol
		(lib_id "antmicroCapacitors0402:C_100n_0402")
		(at 52.705 189.23 90)
		(unit 1)
		(exclude_from_sim no)
		(in_bom yes)
		(on_board yes)
		(dnp no)
		(property "Reference" "C29"
			(at 53.34 184.785 90)
			(effects
				(font
					(size 1.27 1.27)
					(thickness 0.15)
				)
				(justify right)
			)
		)
		(property "Value" "C_100n_0402"
			(at 62.865 168.91 0)
			(effects
				(font
					(size 1.27 1.27)
					(thickness 0.15)
				)
				(justify left bottom)
				(hide yes)
			)
		)
		(property "Footprint" "antmicro-footprints:C_0402_1005Metric"
			(at 65.405 168.91 0)
			(effects
				(font
					(size 1.27 1.27)
					(thickness 0.15)
				)
				(justify left bottom)
				(hide yes)
			)
		)
		(property "Datasheet" "https://www.murata.com/products/productdetail?partno=GRM155R61H104KE14%23"
			(at 67.945 168.91 0)
			(effects
				(font
					(size 1.27 1.27)
					(thickness 0.15)
				)
				(justify left bottom)
				(hide yes)
			)
		)
		(property "Description" ""
			(at 52.705 189.23 0)
			(effects
				(font
					(size 1.27 1.27)
				)
			)
		)
		(property "MPN" "GRM155R61H104KE14D"
			(at 70.485 168.91 0)
			(effects
				(font
					(size 1.27 1.27)
					(thickness 0.15)
				)
				(justify left bottom)
				(hide yes)
			)
		)
		(property "Manufacturer" "Murata"
			(at 73.025 168.91 0)
			(effects
				(font
					(size 1.27 1.27)
					(thickness 0.15)
				)
				(justify left bottom)
				(hide yes)
			)
		)
		(property "License" "Apache-2.0"
			(at 75.565 168.91 0)
			(effects
				(font
					(size 1.27 1.27)
					(thickness 0.15)
				)
				(justify left bottom)
				(hide yes)
			)
		)
		(property "Author" "Antmicro"
			(at 78.105 168.91 0)
			(effects
				(font
					(size 1.27 1.27)
					(thickness 0.15)
				)
				(justify left bottom)
				(hide yes)
			)
		)
		(property "Val" "100n"
			(at 53.34 188.595 90)
			(effects
				(font
					(size 1.27 1.27)
					(thickness 0.15)
				)
				(justify right)
			)
		)
		(property "Voltage" "50V"
			(at 80.645 168.91 0)
			(effects
				(font
					(size 1.27 1.27)
				)
				(justify left bottom)
				(hide yes)
			)
		)
		(property "Dielectric" "X5R"
			(at 83.185 168.91 0)
			(effects
				(font
					(size 1.27 1.27)
				)
				(justify left bottom)
				(hide yes)
			)
		)
		(pin "1"
		)
		(pin "2"
		)
		(instances
			(project "sodimm-ddr5-tester"
				(path ""
					(reference "C29")
					(unit 1)
				)
			)
		)
	)
	(symbol
		(lib_id "antmicroCapacitors0402:C_100n_0402")
		(at 141.605 122.555 90)
		(unit 1)
		(exclude_from_sim no)
		(in_bom yes)
		(on_board yes)
		(dnp no)
		(property "Reference" "C84"
			(at 142.24 118.11 90)
			(effects
				(font
					(size 1.27 1.27)
					(thickness 0.15)
				)
				(justify right)
			)
		)
		(property "Value" "C_100n_0402"
			(at 151.765 102.235 0)
			(effects
				(font
					(size 1.27 1.27)
					(thickness 0.15)
				)
				(justify left bottom)
				(hide yes)
			)
		)
		(property "Footprint" "antmicro-footprints:C_0402_1005Metric"
			(at 154.305 102.235 0)
			(effects
				(font
					(size 1.27 1.27)
					(thickness 0.15)
				)
				(justify left bottom)
				(hide yes)
			)
		)
		(property "Datasheet" "https://www.murata.com/products/productdetail?partno=GRM155R61H104KE14%23"
			(at 156.845 102.235 0)
			(effects
				(font
					(size 1.27 1.27)
					(thickness 0.15)
				)
				(justify left bottom)
				(hide yes)
			)
		)
		(property "Description" ""
			(at 141.605 122.555 0)
			(effects
				(font
					(size 1.27 1.27)
				)
			)
		)
		(property "MPN" "GRM155R61H104KE14D"
			(at 159.385 102.235 0)
			(effects
				(font
					(size 1.27 1.27)
					(thickness 0.15)
				)
				(justify left bottom)
				(hide yes)
			)
		)
		(property "Manufacturer" "Murata"
			(at 161.925 102.235 0)
			(effects
				(font
					(size 1.27 1.27)
					(thickness 0.15)
				)
				(justify left bottom)
				(hide yes)
			)
		)
		(property "License" "Apache-2.0"
			(at 164.465 102.235 0)
			(effects
				(font
					(size 1.27 1.27)
					(thickness 0.15)
				)
				(justify left bottom)
				(hide yes)
			)
		)
		(property "Author" "Antmicro"
			(at 167.005 102.235 0)
			(effects
				(font
					(size 1.27 1.27)
					(thickness 0.15)
				)
				(justify left bottom)
				(hide yes)
			)
		)
		(property "Val" "100n"
			(at 142.24 121.92 90)
			(effects
				(font
					(size 1.27 1.27)
					(thickness 0.15)
				)
				(justify right)
			)
		)
		(property "Voltage" "50V"
			(at 169.545 102.235 0)
			(effects
				(font
					(size 1.27 1.27)
				)
				(justify left bottom)
				(hide yes)
			)
		)
		(property "Dielectric" "X5R"
			(at 172.085 102.235 0)
			(effects
				(font
					(size 1.27 1.27)
				)
				(justify left bottom)
				(hide yes)
			)
		)
		(pin "1"
		)
		(pin "2"
		)
		(instances
			(project "sodimm-ddr5-tester"
				(path ""
					(reference "C84")
					(unit 1)
				)
			)
		)
	)
	(symbol
		(lib_id "antmicroCapacitors0402:C_100n_0402")
		(at 139.065 93.345 90)
		(unit 1)
		(exclude_from_sim no)
		(in_bom yes)
		(on_board yes)
		(dnp no)
		(property "Reference" "C83"
			(at 139.7 88.9 90)
			(effects
				(font
					(size 1.27 1.27)
					(thickness 0.15)
				)
				(justify right)
			)
		)
		(property "Value" "C_100n_0402"
			(at 149.225 73.025 0)
			(effects
				(font
					(size 1.27 1.27)
					(thickness 0.15)
				)
				(justify left bottom)
				(hide yes)
			)
		)
		(property "Footprint" "antmicro-footprints:C_0402_1005Metric"
			(at 151.765 73.025 0)
			(effects
				(font
					(size 1.27 1.27)
					(thickness 0.15)
				)
				(justify left bottom)
				(hide yes)
			)
		)
		(property "Datasheet" "https://www.murata.com/products/productdetail?partno=GRM155R61H104KE14%23"
			(at 154.305 73.025 0)
			(effects
				(font
					(size 1.27 1.27)
					(thickness 0.15)
				)
				(justify left bottom)
				(hide yes)
			)
		)
		(property "Description" ""
			(at 139.065 93.345 0)
			(effects
				(font
					(size 1.27 1.27)
				)
			)
		)
		(property "MPN" "GRM155R61H104KE14D"
			(at 156.845 73.025 0)
			(effects
				(font
					(size 1.27 1.27)
					(thickness 0.15)
				)
				(justify left bottom)
				(hide yes)
			)
		)
		(property "Manufacturer" "Murata"
			(at 159.385 73.025 0)
			(effects
				(font
					(size 1.27 1.27)
					(thickness 0.15)
				)
				(justify left bottom)
				(hide yes)
			)
		)
		(property "License" "Apache-2.0"
			(at 161.925 73.025 0)
			(effects
				(font
					(size 1.27 1.27)
					(thickness 0.15)
				)
				(justify left bottom)
				(hide yes)
			)
		)
		(property "Author" "Antmicro"
			(at 164.465 73.025 0)
			(effects
				(font
					(size 1.27 1.27)
					(thickness 0.15)
				)
				(justify left bottom)
				(hide yes)
			)
		)
		(property "Val" "100n"
			(at 139.7 92.71 90)
			(effects
				(font
					(size 1.27 1.27)
					(thickness 0.15)
				)
				(justify right)
			)
		)
		(property "Voltage" "50V"
			(at 167.005 73.025 0)
			(effects
				(font
					(size 1.27 1.27)
				)
				(justify left bottom)
				(hide yes)
			)
		)
		(property "Dielectric" "X5R"
			(at 169.545 73.025 0)
			(effects
				(font
					(size 1.27 1.27)
				)
				(justify left bottom)
				(hide yes)
			)
		)
		(pin "1"
		)
		(pin "2"
		)
		(instances
			(project "sodimm-ddr5-tester"
				(path ""
					(reference "C83")
					(unit 1)
				)
			)
		)
	)
	(symbol
		(lib_id "antmicropower:GND")
		(at 123.19 191.135 0)
		(unit 1)
		(exclude_from_sim no)
		(in_bom yes)
		(on_board yes)
		(dnp no)
		(fields_autoplaced yes)
		(property "Reference" "#PWR0111"
			(at 123.19 197.485 0)
			(effects
				(font
					(size 1.27 1.27)
				)
				(hide yes)
			)
		)
		(property "Value" "GND"
			(at 125.73 192.405 0)
			(effects
				(font
					(size 1.27 1.27)
					(thickness 0.15)
				)
				(justify left)
			)
		)
		(property "Footprint" ""
			(at 132.08 198.755 0)
			(effects
				(font
					(size 1.27 1.27)
					(thickness 0.15)
				)
				(justify left bottom)
				(hide yes)
			)
		)
		(property "Datasheet" ""
			(at 132.08 203.835 0)
			(effects
				(font
					(size 1.27 1.27)
					(thickness 0.15)
				)
				(justify left bottom)
				(hide yes)
			)
		)
		(property "Description" ""
			(at 132.08 206.375 0)
			(effects
				(font
					(size 1.27 1.27)
				)
				(justify left bottom)
				(hide yes)
			)
		)
		(property "Author" "Antmicro"
			(at 132.08 198.755 0)
			(effects
				(font
					(size 1.27 1.27)
					(thickness 0.15)
				)
				(justify left bottom)
				(hide yes)
			)
		)
		(property "License" "Apache-2.0"
			(at 132.08 201.295 0)
			(effects
				(font
					(size 1.27 1.27)
					(thickness 0.15)
				)
				(justify left bottom)
				(hide yes)
			)
		)
		(pin "1"
		)
		(instances
			(project "sodimm-ddr5-tester"
				(path ""
					(reference "#PWR0111")
					(unit 1)
				)
			)
		)
	)
	(symbol
		(lib_id "antmicropower:GND")
		(at 64.135 94.615 0)
		(unit 1)
		(exclude_from_sim no)
		(in_bom yes)
		(on_board yes)
		(dnp no)
		(fields_autoplaced yes)
		(property "Reference" "#PWR080"
			(at 64.135 100.965 0)
			(effects
				(font
					(size 1.27 1.27)
				)
				(hide yes)
			)
		)
		(property "Value" "GND"
			(at 66.04 95.885 0)
			(effects
				(font
					(size 1.27 1.27)
					(thickness 0.15)
				)
				(justify left)
			)
		)
		(property "Footprint" ""
			(at 73.025 102.235 0)
			(effects
				(font
					(size 1.27 1.27)
					(thickness 0.15)
				)
				(justify left bottom)
				(hide yes)
			)
		)
		(property "Datasheet" ""
			(at 73.025 107.315 0)
			(effects
				(font
					(size 1.27 1.27)
					(thickness 0.15)
				)
				(justify left bottom)
				(hide yes)
			)
		)
		(property "Description" ""
			(at 73.025 109.855 0)
			(effects
				(font
					(size 1.27 1.27)
				)
				(justify left bottom)
				(hide yes)
			)
		)
		(property "Author" "Antmicro"
			(at 73.025 102.235 0)
			(effects
				(font
					(size 1.27 1.27)
					(thickness 0.15)
				)
				(justify left bottom)
				(hide yes)
			)
		)
		(property "License" "Apache-2.0"
			(at 73.025 104.775 0)
			(effects
				(font
					(size 1.27 1.27)
					(thickness 0.15)
				)
				(justify left bottom)
				(hide yes)
			)
		)
		(pin "1"
		)
		(instances
			(project "sodimm-ddr5-tester"
				(path ""
					(reference "#PWR080")
					(unit 1)
				)
			)
		)
	)
	(symbol
		(lib_id "antmicroCapacitors0402:C_100n_0402")
		(at 89.535 93.345 90)
		(unit 1)
		(exclude_from_sim no)
		(in_bom yes)
		(on_board yes)
		(dnp no)
		(property "Reference" "C55"
			(at 90.17 88.9 90)
			(effects
				(font
					(size 1.27 1.27)
					(thickness 0.15)
				)
				(justify right)
			)
		)
		(property "Value" "C_100n_0402"
			(at 99.695 73.025 0)
			(effects
				(font
					(size 1.27 1.27)
					(thickness 0.15)
				)
				(justify left bottom)
				(hide yes)
			)
		)
		(property "Footprint" "antmicro-footprints:C_0402_1005Metric"
			(at 102.235 73.025 0)
			(effects
				(font
					(size 1.27 1.27)
					(thickness 0.15)
				)
				(justify left bottom)
				(hide yes)
			)
		)
		(property "Datasheet" "https://www.murata.com/products/productdetail?partno=GRM155R61H104KE14%23"
			(at 104.775 73.025 0)
			(effects
				(font
					(size 1.27 1.27)
					(thickness 0.15)
				)
				(justify left bottom)
				(hide yes)
			)
		)
		(property "Description" ""
			(at 89.535 93.345 0)
			(effects
				(font
					(size 1.27 1.27)
				)
			)
		)
		(property "MPN" "GRM155R61H104KE14D"
			(at 107.315 73.025 0)
			(effects
				(font
					(size 1.27 1.27)
					(thickness 0.15)
				)
				(justify left bottom)
				(hide yes)
			)
		)
		(property "Manufacturer" "Murata"
			(at 109.855 73.025 0)
			(effects
				(font
					(size 1.27 1.27)
					(thickness 0.15)
				)
				(justify left bottom)
				(hide yes)
			)
		)
		(property "License" "Apache-2.0"
			(at 112.395 73.025 0)
			(effects
				(font
					(size 1.27 1.27)
					(thickness 0.15)
				)
				(justify left bottom)
				(hide yes)
			)
		)
		(property "Author" "Antmicro"
			(at 114.935 73.025 0)
			(effects
				(font
					(size 1.27 1.27)
					(thickness 0.15)
				)
				(justify left bottom)
				(hide yes)
			)
		)
		(property "Val" "100n"
			(at 90.17 92.71 90)
			(effects
				(font
					(size 1.27 1.27)
					(thickness 0.15)
				)
				(justify right)
			)
		)
		(property "Voltage" "50V"
			(at 117.475 73.025 0)
			(effects
				(font
					(size 1.27 1.27)
				)
				(justify left bottom)
				(hide yes)
			)
		)
		(property "Dielectric" "X5R"
			(at 120.015 73.025 0)
			(effects
				(font
					(size 1.27 1.27)
				)
				(justify left bottom)
				(hide yes)
			)
		)
		(pin "1"
		)
		(pin "2"
		)
		(instances
			(project "sodimm-ddr5-tester"
				(path ""
					(reference "C55")
					(unit 1)
				)
			)
		)
	)
	(symbol
		(lib_id "antmicropower:GND")
		(at 130.175 191.135 0)
		(unit 1)
		(exclude_from_sim no)
		(in_bom yes)
		(on_board yes)
		(dnp no)
		(fields_autoplaced yes)
		(property "Reference" "#PWR0114"
			(at 130.175 197.485 0)
			(effects
				(font
					(size 1.27 1.27)
				)
				(hide yes)
			)
		)
		(property "Value" "GND"
			(at 132.08 192.405 0)
			(effects
				(font
					(size 1.27 1.27)
					(thickness 0.15)
				)
				(justify left)
			)
		)
		(property "Footprint" ""
			(at 139.065 198.755 0)
			(effects
				(font
					(size 1.27 1.27)
					(thickness 0.15)
				)
				(justify left bottom)
				(hide yes)
			)
		)
		(property "Datasheet" ""
			(at 139.065 203.835 0)
			(effects
				(font
					(size 1.27 1.27)
					(thickness 0.15)
				)
				(justify left bottom)
				(hide yes)
			)
		)
		(property "Description" ""
			(at 139.065 206.375 0)
			(effects
				(font
					(size 1.27 1.27)
				)
				(justify left bottom)
				(hide yes)
			)
		)
		(property "Author" "Antmicro"
			(at 139.065 198.755 0)
			(effects
				(font
					(size 1.27 1.27)
					(thickness 0.15)
				)
				(justify left bottom)
				(hide yes)
			)
		)
		(property "License" "Apache-2.0"
			(at 139.065 201.295 0)
			(effects
				(font
					(size 1.27 1.27)
					(thickness 0.15)
				)
				(justify left bottom)
				(hide yes)
			)
		)
		(pin "1"
		)
		(instances
			(project "sodimm-ddr5-tester"
				(path ""
					(reference "#PWR0114")
					(unit 1)
				)
			)
		)
	)
	(symbol
		(lib_id "antmicroFPGAChips:XC7K160T-FFG676")
		(at 241.3 82.55 0)
		(unit 10)
		(exclude_from_sim no)
		(in_bom yes)
		(on_board yes)
		(dnp no)
		(fields_autoplaced yes)
		(property "Reference" "U4"
			(at 263.525 76.3184 0)
			(effects
				(font
					(size 1.27 1.27)
				)
			)
		)
		(property "Value" "XC7K160T-FFG676"
			(at 263.525 78.8487 0)
			(effects
				(font
					(size 1.27 1.27)
					(thickness 0.15)
				)
			)
		)
		(property "Footprint" "antmicro-footprints:BGA-676_27x27mm_Layout26x26_P1x1mm_FFG676"
			(at 309.88 85.09 0)
			(effects
				(font
					(size 1.27 1.27)
					(thickness 0.15)
				)
				(justify left bottom)
				(hide yes)
			)
		)
		(property "Datasheet" "https://docs.xilinx.com/v/u/en-US/ds180_7Series_Overview"
			(at 309.88 87.63 0)
			(effects
				(font
					(size 1.27 1.27)
					(thickness 0.15)
				)
				(justify left bottom)
				(hide yes)
			)
		)
		(property "Description" ""
			(at 241.3 82.55 0)
			(effects
				(font
					(size 1.27 1.27)
				)
			)
		)
		(property "MPN" "XC7K160T-FFG676"
			(at 241.3 82.55 0)
			(effects
				(font
					(size 1.27 1.27)
				)
				(hide yes)
			)
		)
		(property "Author" "Antmicro"
			(at 309.88 90.17 0)
			(effects
				(font
					(size 1.27 1.27)
					(thickness 0.15)
				)
				(justify left bottom)
				(hide yes)
			)
		)
		(property "License" "Apache-2.0"
			(at 309.88 92.71 0)
			(effects
				(font
					(size 1.27 1.27)
					(thickness 0.15)
				)
				(justify left bottom)
				(hide yes)
			)
		)
		(property "Manufacturer" "AMD-Xilinx"
			(at 241.3 82.55 0)
			(effects
				(font
					(size 1.27 1.27)
				)
				(hide yes)
			)
		)
		(pin "AA21"
		)
		(pin "AA22"
		)
		(pin "AA23"
		)
		(pin "AA24"
		)
		(pin "AA25"
		)
		(pin "AB21"
		)
		(pin "AB22"
		)
		(pin "AB24"
		)
		(pin "AB25"
		)
		(pin "AB26"
		)
		(pin "AC21"
		)
		(pin "AC22"
		)
		(pin "AC23"
		)
		(pin "AC24"
		)
		(pin "AC25"
		)
		(pin "AC26"
		)
		(pin "AD21"
		)
		(pin "AD22"
		)
		(pin "AD23"
		)
		(pin "AD24"
		)
		(pin "AD25"
		)
		(pin "AD26"
		)
		(pin "AE21"
		)
		(pin "AE22"
		)
		(pin "AE23"
		)
		(pin "AE25"
		)
		(pin "AE26"
		)
		(pin "AF22"
		)
		(pin "AF23"
		)
		(pin "AF24"
		)
		(pin "AF25"
		)
		(pin "AF26"
		)
		(pin "U21"
		)
		(pin "U22"
		)
		(pin "U23"
		)
		(pin "U24"
		)
		(pin "U25"
		)
		(pin "U26"
		)
		(pin "V20"
		)
		(pin "V21"
		)
		(pin "V22"
		)
		(pin "V23"
		)
		(pin "V24"
		)
		(pin "V26"
		)
		(pin "W20"
		)
		(pin "W21"
		)
		(pin "W23"
		)
		(pin "W24"
		)
		(pin "W25"
		)
		(pin "W26"
		)
		(pin "Y20"
		)
		(pin "Y21"
		)
		(pin "Y22"
		)
		(pin "Y23"
		)
		(pin "Y24"
		)
		(pin "Y25"
		)
		(pin "Y26"
		)
		(pin "K24"
		)
		(pin "K25"
		)
		(pin "K26"
		)
		(pin "L24"
		)
		(pin "L25"
		)
		(pin "M19"
		)
		(pin "M20"
		)
		(pin "M21"
		)
		(pin "M22"
		)
		(pin "M24"
		)
		(pin "M25"
		)
		(pin "M26"
		)
		(pin "N16"
		)
		(pin "N17"
		)
		(pin "N18"
		)
		(pin "N19"
		)
		(pin "N21"
		)
		(pin "N22"
		)
		(pin "N23"
		)
		(pin "N24"
		)
		(pin "N25"
		)
		(pin "N26"
		)
		(pin "P16"
		)
		(pin "P18"
		)
		(pin "P19"
		)
		(pin "P20"
		)
		(pin "P21"
		)
		(pin "P22"
		)
		(pin "P23"
		)
		(pin "P24"
		)
		(pin "P25"
		)
		(pin "P26"
		)
		(pin "R16"
		)
		(pin "R17"
		)
		(pin "R18"
		)
		(pin "R19"
		)
		(pin "R20"
		)
		(pin "R21"
		)
		(pin "R22"
		)
		(pin "R23"
		)
		(pin "R25"
		)
		(pin "R26"
		)
		(pin "T16"
		)
		(pin "T17"
		)
		(pin "T18"
		)
		(pin "T19"
		)
		(pin "T20"
		)
		(pin "T22"
		)
		(pin "T23"
		)
		(pin "T24"
		)
		(pin "T25"
		)
		(pin "T26"
		)
		(pin "U16"
		)
		(pin "U17"
		)
		(pin "U19"
		)
		(pin "U20"
		)
		(pin "A20"
		)
		(pin "A21"
		)
		(pin "A22"
		)
		(pin "A23"
		)
		(pin "A24"
		)
		(pin "A25"
		)
		(pin "B20"
		)
		(pin "B21"
		)
		(pin "B22"
		)
		(pin "B24"
		)
		(pin "B25"
		)
		(pin "B26"
		)
		(pin "C21"
		)
		(pin "C22"
		)
		(pin "C23"
		)
		(pin "C24"
		)
		(pin "C25"
		)
		(pin "C26"
		)
		(pin "D21"
		)
		(pin "D22"
		)
		(pin "D23"
		)
		(pin "D24"
		)
		(pin "D25"
		)
		(pin "D26"
		)
		(pin "E21"
		)
		(pin "E22"
		)
		(pin "E23"
		)
		(pin "E25"
		)
		(pin "E26"
		)
		(pin "F22"
		)
		(pin "F23"
		)
		(pin "F24"
		)
		(pin "F25"
		)
		(pin "F26"
		)
		(pin "G21"
		)
		(pin "G22"
		)
		(pin "G23"
		)
		(pin "G24"
		)
		(pin "G25"
		)
		(pin "G26"
		)
		(pin "H21"
		)
		(pin "H22"
		)
		(pin "H23"
		)
		(pin "H24"
		)
		(pin "H26"
		)
		(pin "J21"
		)
		(pin "J23"
		)
		(pin "J24"
		)
		(pin "J25"
		)
		(pin "J26"
		)
		(pin "K21"
		)
		(pin "K22"
		)
		(pin "K23"
		)
		(pin "L21"
		)
		(pin "L22"
		)
		(pin "L23"
		)
		(pin "A17"
		)
		(pin "A18"
		)
		(pin "A19"
		)
		(pin "B16"
		)
		(pin "B17"
		)
		(pin "B18"
		)
		(pin "B19"
		)
		(pin "C16"
		)
		(pin "C17"
		)
		(pin "C18"
		)
		(pin "C19"
		)
		(pin "D15"
		)
		(pin "D16"
		)
		(pin "D18"
		)
		(pin "D19"
		)
		(pin "D20"
		)
		(pin "E15"
		)
		(pin "E16"
		)
		(pin "E17"
		)
		(pin "E18"
		)
		(pin "E19"
		)
		(pin "E20"
		)
		(pin "F15"
		)
		(pin "F16"
		)
		(pin "F17"
		)
		(pin "F18"
		)
		(pin "F19"
		)
		(pin "F20"
		)
		(pin "G15"
		)
		(pin "G16"
		)
		(pin "G17"
		)
		(pin "G19"
		)
		(pin "G20"
		)
		(pin "H16"
		)
		(pin "H17"
		)
		(pin "H18"
		)
		(pin "H19"
		)
		(pin "H20"
		)
		(pin "J15"
		)
		(pin "J16"
		)
		(pin "J17"
		)
		(pin "J18"
		)
		(pin "J19"
		)
		(pin "J20"
		)
		(pin "K15"
		)
		(pin "K16"
		)
		(pin "K17"
		)
		(pin "K18"
		)
		(pin "K20"
		)
		(pin "L17"
		)
		(pin "L18"
		)
		(pin "L19"
		)
		(pin "L20"
		)
		(pin "M16"
		)
		(pin "M17"
		)
		(pin "M18"
		)
		(pin "A10"
		)
		(pin "A11"
		)
		(pin "A12"
		)
		(pin "A13"
		)
		(pin "A14"
		)
		(pin "A15"
		)
		(pin "A8"
		)
		(pin "A9"
		)
		(pin "B10"
		)
		(pin "B11"
		)
		(pin "B12"
		)
		(pin "B14"
		)
		(pin "B15"
		)
		(pin "B8"
		)
		(pin "B9"
		)
		(pin "C11"
		)
		(pin "C12"
		)
		(pin "C13"
		)
		(pin "C14"
		)
		(pin "C15"
		)
		(pin "C9"
		)
		(pin "D10"
		)
		(pin "D11"
		)
		(pin "D12"
		)
		(pin "D13"
		)
		(pin "D14"
		)
		(pin "D8"
		)
		(pin "D9"
		)
		(pin "E10"
		)
		(pin "E11"
		)
		(pin "E12"
		)
		(pin "E13"
		)
		(pin "E9"
		)
		(pin "F10"
		)
		(pin "F12"
		)
		(pin "F13"
		)
		(pin "F14"
		)
		(pin "F8"
		)
		(pin "F9"
		)
		(pin "G10"
		)
		(pin "G11"
		)
		(pin "G12"
		)
		(pin "G13"
		)
		(pin "G14"
		)
		(pin "G9"
		)
		(pin "H10"
		)
		(pin "H11"
		)
		(pin "H12"
		)
		(pin "H13"
		)
		(pin "H14"
		)
		(pin "H8"
		)
		(pin "H9"
		)
		(pin "J10"
		)
		(pin "J11"
		)
		(pin "J13"
		)
		(pin "J14"
		)
		(pin "J8"
		)
		(pin "AA14"
		)
		(pin "AA15"
		)
		(pin "AA17"
		)
		(pin "AA18"
		)
		(pin "AA19"
		)
		(pin "AA20"
		)
		(pin "AB14"
		)
		(pin "AB15"
		)
		(pin "AB16"
		)
		(pin "AB17"
		)
		(pin "AB18"
		)
		(pin "AB19"
		)
		(pin "AB20"
		)
		(pin "AC14"
		)
		(pin "AC15"
		)
		(pin "AC16"
		)
		(pin "AC17"
		)
		(pin "AC18"
		)
		(pin "AC19"
		)
		(pin "AD14"
		)
		(pin "AD15"
		)
		(pin "AD16"
		)
		(pin "AD18"
		)
		(pin "AD19"
		)
		(pin "AD20"
		)
		(pin "AE15"
		)
		(pin "AE16"
		)
		(pin "AE17"
		)
		(pin "AE18"
		)
		(pin "AE19"
		)
		(pin "AE20"
		)
		(pin "AF14"
		)
		(pin "AF15"
		)
		(pin "AF16"
		)
		(pin "AF17"
		)
		(pin "AF18"
		)
		(pin "AF19"
		)
		(pin "AF20"
		)
		(pin "V13"
		)
		(pin "V14"
		)
		(pin "V16"
		)
		(pin "V17"
		)
		(pin "V18"
		)
		(pin "V19"
		)
		(pin "W13"
		)
		(pin "W14"
		)
		(pin "W15"
		)
		(pin "W16"
		)
		(pin "W17"
		)
		(pin "W18"
		)
		(pin "W19"
		)
		(pin "Y14"
		)
		(pin "Y15"
		)
		(pin "Y16"
		)
		(pin "Y17"
		)
		(pin "Y18"
		)
		(pin "AA10"
		)
		(pin "AA11"
		)
		(pin "AA12"
		)
		(pin "AA13"
		)
		(pin "AA7"
		)
		(pin "AA8"
		)
		(pin "AA9"
		)
		(pin "AB10"
		)
		(pin "AB11"
		)
		(pin "AB12"
		)
		(pin "AB7"
		)
		(pin "AB8"
		)
		(pin "AB9"
		)
		(pin "AC11"
		)
		(pin "AC12"
		)
		(pin "AC13"
		)
		(pin "AC7"
		)
		(pin "AC8"
		)
		(pin "AC9"
		)
		(pin "AD10"
		)
		(pin "AD11"
		)
		(pin "AD12"
		)
		(pin "AD13"
		)
		(pin "AD8"
		)
		(pin "AD9"
		)
		(pin "AE10"
		)
		(pin "AE11"
		)
		(pin "AE12"
		)
		(pin "AE13"
		)
		(pin "AE7"
		)
		(pin "AE8"
		)
		(pin "AE9"
		)
		(pin "AF10"
		)
		(pin "AF12"
		)
		(pin "AF13"
		)
		(pin "AF7"
		)
		(pin "AF8"
		)
		(pin "AF9"
		)
		(pin "U9"
		)
		(pin "V10"
		)
		(pin "V11"
		)
		(pin "V12"
		)
		(pin "V7"
		)
		(pin "V8"
		)
		(pin "V9"
		)
		(pin "W10"
		)
		(pin "W11"
		)
		(pin "W7"
		)
		(pin "W8"
		)
		(pin "W9"
		)
		(pin "Y10"
		)
		(pin "Y11"
		)
		(pin "Y12"
		)
		(pin "Y13"
		)
		(pin "Y7"
		)
		(pin "Y8"
		)
		(pin "AA1"
		)
		(pin "AA2"
		)
		(pin "AA3"
		)
		(pin "AA4"
		)
		(pin "AA5"
		)
		(pin "AB1"
		)
		(pin "AB2"
		)
		(pin "AB4"
		)
		(pin "AB5"
		)
		(pin "AB6"
		)
		(pin "AC1"
		)
		(pin "AC2"
		)
		(pin "AC3"
		)
		(pin "AC4"
		)
		(pin "AC5"
		)
		(pin "AC6"
		)
		(pin "AD1"
		)
		(pin "AD2"
		)
		(pin "AD3"
		)
		(pin "AD4"
		)
		(pin "AD5"
		)
		(pin "AD6"
		)
		(pin "AE1"
		)
		(pin "AE2"
		)
		(pin "AE3"
		)
		(pin "AE5"
		)
		(pin "AE6"
		)
		(pin "AF2"
		)
		(pin "AF3"
		)
		(pin "AF4"
		)
		(pin "AF5"
		)
		(pin "AF6"
		)
		(pin "T7"
		)
		(pin "U1"
		)
		(pin "U2"
		)
		(pin "U3"
		)
		(pin "U4"
		)
		(pin "U5"
		)
		(pin "U6"
		)
		(pin "U7"
		)
		(pin "V1"
		)
		(pin "V2"
		)
		(pin "V3"
		)
		(pin "V4"
		)
		(pin "V6"
		)
		(pin "W1"
		)
		(pin "W3"
		)
		(pin "W4"
		)
		(pin "W5"
		)
		(pin "W6"
		)
		(pin "Y1"
		)
		(pin "Y2"
		)
		(pin "Y3"
		)
		(pin "Y4"
		)
		(pin "Y5"
		)
		(pin "Y6"
		)
		(pin "A3"
		)
		(pin "A4"
		)
		(pin "B1"
		)
		(pin "B2"
		)
		(pin "B5"
		)
		(pin "B6"
		)
		(pin "C3"
		)
		(pin "C4"
		)
		(pin "D1"
		)
		(pin "D2"
		)
		(pin "D5"
		)
		(pin "D6"
		)
		(pin "E3"
		)
		(pin "E4"
		)
		(pin "F1"
		)
		(pin "F2"
		)
		(pin "F5"
		)
		(pin "F6"
		)
		(pin "G3"
		)
		(pin "G4"
		)
		(pin "H1"
		)
		(pin "H2"
		)
		(pin "H5"
		)
		(pin "H6"
		)
		(pin "J3"
		)
		(pin "J4"
		)
		(pin "K1"
		)
		(pin "K2"
		)
		(pin "K5"
		)
		(pin "K6"
		)
		(pin "L3"
		)
		(pin "L4"
		)
		(pin "M1"
		)
		(pin "M2"
		)
		(pin "N3"
		)
		(pin "N4"
		)
		(pin "P1"
		)
		(pin "P2"
		)
		(pin "R3"
		)
		(pin "R4"
		)
		(pin "A1"
		)
		(pin "A16"
		)
		(pin "A2"
		)
		(pin "A26"
		)
		(pin "A5"
		)
		(pin "A6"
		)
		(pin "A7"
		)
		(pin "AA16"
		)
		(pin "AA26"
		)
		(pin "AA6"
		)
		(pin "AB13"
		)
		(pin "AB23"
		)
		(pin "AB3"
		)
		(pin "AC10"
		)
		(pin "AC20"
		)
		(pin "AD17"
		)
		(pin "AD7"
		)
		(pin "AE14"
		)
		(pin "AE24"
		)
		(pin "AE4"
		)
		(pin "AF1"
		)
		(pin "AF11"
		)
		(pin "AF21"
		)
		(pin "B13"
		)
		(pin "B23"
		)
		(pin "B3"
		)
		(pin "B4"
		)
		(pin "B7"
		)
		(pin "C1"
		)
		(pin "C10"
		)
		(pin "C2"
		)
		(pin "C20"
		)
		(pin "C5"
		)
		(pin "C6"
		)
		(pin "C7"
		)
		(pin "D17"
		)
		(pin "D3"
		)
		(pin "D4"
		)
		(pin "D7"
		)
		(pin "E1"
		)
		(pin "E14"
		)
		(pin "E2"
		)
		(pin "E24"
		)
		(pin "E5"
		)
		(pin "E6"
		)
		(pin "E7"
		)
		(pin "E8"
		)
		(pin "F11"
		)
		(pin "F21"
		)
		(pin "F3"
		)
		(pin "F4"
		)
		(pin "F7"
		)
		(pin "G1"
		)
		(pin "G18"
		)
		(pin "G2"
		)
		(pin "G5"
		)
		(pin "G6"
		)
		(pin "G8"
		)
		(pin "H15"
		)
		(pin "H25"
		)
		(pin "H3"
		)
		(pin "H4"
		)
		(pin "H7"
		)
		(pin "J1"
		)
		(pin "J12"
		)
		(pin "J2"
		)
		(pin "J22"
		)
		(pin "J5"
		)
		(pin "J6"
		)
		(pin "J9"
		)
		(pin "K10"
		)
		(pin "K11"
		)
		(pin "K12"
		)
		(pin "K13"
		)
		(pin "K14"
		)
		(pin "K19"
		)
		(pin "K3"
		)
		(pin "K4"
		)
		(pin "K7"
		)
		(pin "K8"
		)
		(pin "K9"
		)
		(pin "L1"
		)
		(pin "L10"
		)
		(pin "L11"
		)
		(pin "L12"
		)
		(pin "L13"
		)
		(pin "L14"
		)
		(pin "L15"
		)
		(pin "L16"
		)
		(pin "L2"
		)
		(pin "L26"
		)
		(pin "L5"
		)
		(pin "L6"
		)
		(pin "L9"
		)
		(pin "M10"
		)
		(pin "M11"
		)
		(pin "M12"
		)
		(pin "M13"
		)
		(pin "M14"
		)
		(pin "M15"
		)
		(pin "M23"
		)
		(pin "M3"
		)
		(pin "M4"
		)
		(pin "M5"
		)
		(pin "M6"
		)
		(pin "M7"
		)
		(pin "M8"
		)
		(pin "M9"
		)
		(pin "N1"
		)
		(pin "N10"
		)
		(pin "N13"
		)
		(pin "N14"
		)
		(pin "N15"
		)
		(pin "N2"
		)
		(pin "N20"
		)
		(pin "N5"
		)
		(pin "N6"
		)
		(pin "N7"
		)
		(pin "N9"
		)
		(pin "P10"
		)
		(pin "P13"
		)
		(pin "P14"
		)
		(pin "P15"
		)
		(pin "P17"
		)
		(pin "P3"
		)
		(pin "P4"
		)
		(pin "P8"
		)
		(pin "P9"
		)
		(pin "R1"
		)
		(pin "R10"
		)
		(pin "R13"
		)
		(pin "R14"
		)
		(pin "R15"
		)
		(pin "R2"
		)
		(pin "R24"
		)
		(pin "R5"
		)
		(pin "R8"
		)
		(pin "R9"
		)
		(pin "T1"
		)
		(pin "T10"
		)
		(pin "T11"
		)
		(pin "T12"
		)
		(pin "T13"
		)
		(pin "T14"
		)
		(pin "T15"
		)
		(pin "T21"
		)
		(pin "T3"
		)
		(pin "T4"
		)
		(pin "T8"
		)
		(pin "T9"
		)
		(pin "U10"
		)
		(pin "U11"
		)
		(pin "U12"
		)
		(pin "U13"
		)
		(pin "U14"
		)
		(pin "U15"
		)
		(pin "U18"
		)
		(pin "U8"
		)
		(pin "V15"
		)
		(pin "V25"
		)
		(pin "V5"
		)
		(pin "W12"
		)
		(pin "W2"
		)
		(pin "W22"
		)
		(pin "Y19"
		)
		(pin "Y9"
		)
		(pin "C8"
		)
		(pin "G7"
		)
		(pin "J7"
		)
		(pin "L7"
		)
		(pin "L8"
		)
		(pin "N11"
		)
		(pin "N12"
		)
		(pin "N8"
		)
		(pin "P11"
		)
		(pin "P12"
		)
		(pin "P5"
		)
		(pin "P6"
		)
		(pin "P7"
		)
		(pin "R11"
		)
		(pin "R12"
		)
		(pin "R6"
		)
		(pin "R7"
		)
		(pin "T2"
		)
		(pin "T5"
		)
		(pin "T6"
		)
		(instances
			(project "sodimm-ddr5-tester"
				(path ""
					(reference "U4")
					(unit 10)
				)
			)
		)
	)
	(symbol
		(lib_id "antmicropower:GND")
		(at 66.04 248.92 0)
		(unit 1)
		(exclude_from_sim no)
		(in_bom yes)
		(on_board yes)
		(dnp no)
		(fields_autoplaced yes)
		(property "Reference" "#PWR086"
			(at 66.04 255.27 0)
			(effects
				(font
					(size 1.27 1.27)
				)
				(hide yes)
			)
		)
		(property "Value" "GND"
			(at 68.58 250.19 0)
			(effects
				(font
					(size 1.27 1.27)
					(thickness 0.15)
				)
				(justify left)
			)
		)
		(property "Footprint" ""
			(at 74.93 256.54 0)
			(effects
				(font
					(size 1.27 1.27)
					(thickness 0.15)
				)
				(justify left bottom)
				(hide yes)
			)
		)
		(property "Datasheet" ""
			(at 74.93 261.62 0)
			(effects
				(font
					(size 1.27 1.27)
					(thickness 0.15)
				)
				(justify left bottom)
				(hide yes)
			)
		)
		(property "Description" ""
			(at 74.93 264.16 0)
			(effects
				(font
					(size 1.27 1.27)
				)
				(justify left bottom)
				(hide yes)
			)
		)
		(property "Author" "Antmicro"
			(at 74.93 256.54 0)
			(effects
				(font
					(size 1.27 1.27)
					(thickness 0.15)
				)
				(justify left bottom)
				(hide yes)
			)
		)
		(property "License" "Apache-2.0"
			(at 74.93 259.08 0)
			(effects
				(font
					(size 1.27 1.27)
					(thickness 0.15)
				)
				(justify left bottom)
				(hide yes)
			)
		)
		(pin "1"
		)
		(instances
			(project "sodimm-ddr5-tester"
				(path ""
					(reference "#PWR086")
					(unit 1)
				)
			)
		)
	)
	(symbol
		(lib_id "antmicropower:GND")
		(at 137.16 162.56 0)
		(unit 1)
		(exclude_from_sim no)
		(in_bom yes)
		(on_board yes)
		(dnp no)
		(fields_autoplaced yes)
		(property "Reference" "#PWR078"
			(at 137.16 168.91 0)
			(effects
				(font
					(size 1.27 1.27)
				)
				(hide yes)
			)
		)
		(property "Value" "GND"
			(at 139.7 163.83 0)
			(effects
				(font
					(size 1.27 1.27)
					(thickness 0.15)
				)
				(justify left)
			)
		)
		(property "Footprint" ""
			(at 146.05 170.18 0)
			(effects
				(font
					(size 1.27 1.27)
					(thickness 0.15)
				)
				(justify left bottom)
				(hide yes)
			)
		)
		(property "Datasheet" ""
			(at 146.05 175.26 0)
			(effects
				(font
					(size 1.27 1.27)
					(thickness 0.15)
				)
				(justify left bottom)
				(hide yes)
			)
		)
		(property "Description" ""
			(at 146.05 177.8 0)
			(effects
				(font
					(size 1.27 1.27)
				)
				(justify left bottom)
				(hide yes)
			)
		)
		(property "Author" "Antmicro"
			(at 146.05 170.18 0)
			(effects
				(font
					(size 1.27 1.27)
					(thickness 0.15)
				)
				(justify left bottom)
				(hide yes)
			)
		)
		(property "License" "Apache-2.0"
			(at 146.05 172.72 0)
			(effects
				(font
					(size 1.27 1.27)
					(thickness 0.15)
				)
				(justify left bottom)
				(hide yes)
			)
		)
		(pin "1"
		)
		(instances
			(project "sodimm-ddr5-tester"
				(path ""
					(reference "#PWR078")
					(unit 1)
				)
			)
		)
	)
	(symbol
		(lib_id "antmicroCapacitors0402:C_4u7_0402")
		(at 129.54 62.23 270)
		(unit 1)
		(exclude_from_sim no)
		(in_bom yes)
		(on_board yes)
		(dnp no)
		(property "Reference" "C71"
			(at 130.175 62.865 90)
			(effects
				(font
					(size 1.27 1.27)
				)
				(justify left)
			)
		)
		(property "Value" "C_4u7_0402"
			(at 119.38 82.55 0)
			(effects
				(font
					(size 1.27 1.27)
					(thickness 0.15)
				)
				(justify left bottom)
				(hide yes)
			)
		)
		(property "Footprint" "antmicro-footprints:C_0402_1005Metric"
			(at 116.84 82.55 0)
			(effects
				(font
					(size 1.27 1.27)
					(thickness 0.15)
				)
				(justify left bottom)
				(hide yes)
			)
		)
		(property "Datasheet" "https://www.murata.com/products/productdetail?partno=GRM155R61A475MEAA%23"
			(at 114.3 82.55 0)
			(effects
				(font
					(size 1.27 1.27)
					(thickness 0.15)
				)
				(justify left bottom)
				(hide yes)
			)
		)
		(property "Description" ""
			(at 129.54 62.23 0)
			(effects
				(font
					(size 1.27 1.27)
				)
			)
		)
		(property "Manufacturer" "Murata"
			(at 109.22 82.55 0)
			(effects
				(font
					(size 1.27 1.27)
					(thickness 0.15)
				)
				(justify left bottom)
				(hide yes)
			)
		)
		(property "MPN" "GRM155R61A475MEAAD"
			(at 111.76 82.55 0)
			(effects
				(font
					(size 1.27 1.27)
					(thickness 0.15)
				)
				(justify left bottom)
				(hide yes)
			)
		)
		(property "Val" "4u7"
			(at 130.175 66.675 90)
			(effects
				(font
					(size 1.27 1.27)
					(thickness 0.15)
				)
				(justify left)
			)
		)
		(property "License" "Apache-2.0"
			(at 106.68 82.55 0)
			(effects
				(font
					(size 1.27 1.27)
					(thickness 0.15)
				)
				(justify left bottom)
				(hide yes)
			)
		)
		(property "Author" "Antmicro"
			(at 104.14 82.55 0)
			(effects
				(font
					(size 1.27 1.27)
					(thickness 0.15)
				)
				(justify left bottom)
				(hide yes)
			)
		)
		(property "Voltage" ""
			(at 101.6 82.55 0)
			(effects
				(font
					(size 1.27 1.27)
				)
				(justify left bottom)
				(hide yes)
			)
		)
		(property "Dielectric" ""
			(at 99.06 82.55 0)
			(effects
				(font
					(size 1.27 1.27)
				)
				(justify left bottom)
				(hide yes)
			)
		)
		(pin "1"
		)
		(pin "2"
		)
		(instances
			(project "sodimm-ddr5-tester"
				(path ""
					(reference "C71")
					(unit 1)
				)
			)
		)
	)
	(symbol
		(lib_id "antmicroCapacitors0402:C_100n_0402")
		(at 66.04 247.65 90)
		(unit 1)
		(exclude_from_sim no)
		(in_bom yes)
		(on_board yes)
		(dnp no)
		(property "Reference" "C39"
			(at 66.675 243.205 90)
			(effects
				(font
					(size 1.27 1.27)
					(thickness 0.15)
				)
				(justify right)
			)
		)
		(property "Value" "C_100n_0402"
			(at 76.2 227.33 0)
			(effects
				(font
					(size 1.27 1.27)
					(thickness 0.15)
				)
				(justify left bottom)
				(hide yes)
			)
		)
		(property "Footprint" "antmicro-footprints:C_0402_1005Metric"
			(at 78.74 227.33 0)
			(effects
				(font
					(size 1.27 1.27)
					(thickness 0.15)
				)
				(justify left bottom)
				(hide yes)
			)
		)
		(property "Datasheet" "https://www.murata.com/products/productdetail?partno=GRM155R61H104KE14%23"
			(at 81.28 227.33 0)
			(effects
				(font
					(size 1.27 1.27)
					(thickness 0.15)
				)
				(justify left bottom)
				(hide yes)
			)
		)
		(property "Description" ""
			(at 66.04 247.65 0)
			(effects
				(font
					(size 1.27 1.27)
				)
			)
		)
		(property "MPN" "GRM155R61H104KE14D"
			(at 83.82 227.33 0)
			(effects
				(font
					(size 1.27 1.27)
					(thickness 0.15)
				)
				(justify left bottom)
				(hide yes)
			)
		)
		(property "Manufacturer" "Murata"
			(at 86.36 227.33 0)
			(effects
				(font
					(size 1.27 1.27)
					(thickness 0.15)
				)
				(justify left bottom)
				(hide yes)
			)
		)
		(property "License" "Apache-2.0"
			(at 88.9 227.33 0)
			(effects
				(font
					(size 1.27 1.27)
					(thickness 0.15)
				)
				(justify left bottom)
				(hide yes)
			)
		)
		(property "Author" "Antmicro"
			(at 91.44 227.33 0)
			(effects
				(font
					(size 1.27 1.27)
					(thickness 0.15)
				)
				(justify left bottom)
				(hide yes)
			)
		)
		(property "Val" "100n"
			(at 66.675 247.015 90)
			(effects
				(font
					(size 1.27 1.27)
					(thickness 0.15)
				)
				(justify right)
			)
		)
		(property "Voltage" "50V"
			(at 93.98 227.33 0)
			(effects
				(font
					(size 1.27 1.27)
				)
				(justify left bottom)
				(hide yes)
			)
		)
		(property "Dielectric" "X5R"
			(at 96.52 227.33 0)
			(effects
				(font
					(size 1.27 1.27)
				)
				(justify left bottom)
				(hide yes)
			)
		)
		(pin "1"
		)
		(pin "2"
		)
		(instances
			(project "sodimm-ddr5-tester"
				(path ""
					(reference "C39")
					(unit 1)
				)
			)
		)
	)
	(symbol
		(lib_id "antmicroCapacitors0402:C_4u7_0402")
		(at 331.47 57.15 270)
		(unit 1)
		(exclude_from_sim no)
		(in_bom yes)
		(on_board yes)
		(dnp no)
		(property "Reference" "C102"
			(at 331.47 57.15 90)
			(effects
				(font
					(size 1.27 1.27)
				)
				(justify left)
			)
		)
		(property "Value" "C_4u7_0402"
			(at 321.31 77.47 0)
			(effects
				(font
					(size 1.27 1.27)
					(thickness 0.15)
				)
				(justify left bottom)
				(hide yes)
			)
		)
		(property "Footprint" "antmicro-footprints:C_0402_1005Metric"
			(at 318.77 77.47 0)
			(effects
				(font
					(size 1.27 1.27)
					(thickness 0.15)
				)
				(justify left bottom)
				(hide yes)
			)
		)
		(property "Datasheet" "https://www.murata.com/products/productdetail?partno=GRM155R61A475MEAA%23"
			(at 316.23 77.47 0)
			(effects
				(font
					(size 1.27 1.27)
					(thickness 0.15)
				)
				(justify left bottom)
				(hide yes)
			)
		)
		(property "Description" ""
			(at 331.47 57.15 0)
			(effects
				(font
					(size 1.27 1.27)
				)
			)
		)
		(property "Manufacturer" "Murata"
			(at 311.15 77.47 0)
			(effects
				(font
					(size 1.27 1.27)
					(thickness 0.15)
				)
				(justify left bottom)
				(hide yes)
			)
		)
		(property "MPN" "GRM155R61A475MEAAD"
			(at 313.69 77.47 0)
			(effects
				(font
					(size 1.27 1.27)
					(thickness 0.15)
				)
				(justify left bottom)
				(hide yes)
			)
		)
		(property "Val" "4u7"
			(at 332.105 61.595 90)
			(effects
				(font
					(size 1.27 1.27)
					(thickness 0.15)
				)
				(justify left)
			)
		)
		(property "License" "Apache-2.0"
			(at 308.61 77.47 0)
			(effects
				(font
					(size 1.27 1.27)
					(thickness 0.15)
				)
				(justify left bottom)
				(hide yes)
			)
		)
		(property "Author" "Antmicro"
			(at 306.07 77.47 0)
			(effects
				(font
					(size 1.27 1.27)
					(thickness 0.15)
				)
				(justify left bottom)
				(hide yes)
			)
		)
		(property "Voltage" ""
			(at 303.53 77.47 0)
			(effects
				(font
					(size 1.27 1.27)
				)
				(justify left bottom)
				(hide yes)
			)
		)
		(property "Dielectric" ""
			(at 300.99 77.47 0)
			(effects
				(font
					(size 1.27 1.27)
				)
				(justify left bottom)
				(hide yes)
			)
		)
		(pin "1"
		)
		(pin "2"
		)
		(instances
			(project "sodimm-ddr5-tester"
				(path ""
					(reference "C102")
					(unit 1)
				)
			)
		)
	)
	(symbol
		(lib_id "antmicroCapacitors0402:C_100n_0402")
		(at 157.48 220.345 90)
		(unit 1)
		(exclude_from_sim no)
		(in_bom yes)
		(on_board yes)
		(dnp no)
		(property "Reference" "C95"
			(at 158.115 215.9 90)
			(effects
				(font
					(size 1.27 1.27)
					(thickness 0.15)
				)
				(justify right)
			)
		)
		(property "Value" "C_100n_0402"
			(at 167.64 200.025 0)
			(effects
				(font
					(size 1.27 1.27)
					(thickness 0.15)
				)
				(justify left bottom)
				(hide yes)
			)
		)
		(property "Footprint" "antmicro-footprints:C_0402_1005Metric"
			(at 170.18 200.025 0)
			(effects
				(font
					(size 1.27 1.27)
					(thickness 0.15)
				)
				(justify left bottom)
				(hide yes)
			)
		)
		(property "Datasheet" "https://www.murata.com/products/productdetail?partno=GRM155R61H104KE14%23"
			(at 172.72 200.025 0)
			(effects
				(font
					(size 1.27 1.27)
					(thickness 0.15)
				)
				(justify left bottom)
				(hide yes)
			)
		)
		(property "Description" ""
			(at 157.48 220.345 0)
			(effects
				(font
					(size 1.27 1.27)
				)
			)
		)
		(property "MPN" "GRM155R61H104KE14D"
			(at 175.26 200.025 0)
			(effects
				(font
					(size 1.27 1.27)
					(thickness 0.15)
				)
				(justify left bottom)
				(hide yes)
			)
		)
		(property "Manufacturer" "Murata"
			(at 177.8 200.025 0)
			(effects
				(font
					(size 1.27 1.27)
					(thickness 0.15)
				)
				(justify left bottom)
				(hide yes)
			)
		)
		(property "License" "Apache-2.0"
			(at 180.34 200.025 0)
			(effects
				(font
					(size 1.27 1.27)
					(thickness 0.15)
				)
				(justify left bottom)
				(hide yes)
			)
		)
		(property "Author" "Antmicro"
			(at 182.88 200.025 0)
			(effects
				(font
					(size 1.27 1.27)
					(thickness 0.15)
				)
				(justify left bottom)
				(hide yes)
			)
		)
		(property "Val" "100n"
			(at 158.115 219.71 90)
			(effects
				(font
					(size 1.27 1.27)
					(thickness 0.15)
				)
				(justify right)
			)
		)
		(property "Voltage" "50V"
			(at 185.42 200.025 0)
			(effects
				(font
					(size 1.27 1.27)
				)
				(justify left bottom)
				(hide yes)
			)
		)
		(property "Dielectric" "X5R"
			(at 187.96 200.025 0)
			(effects
				(font
					(size 1.27 1.27)
				)
				(justify left bottom)
				(hide yes)
			)
		)
		(pin "1"
		)
		(pin "2"
		)
		(instances
			(project "sodimm-ddr5-tester"
				(path ""
					(reference "C95")
					(unit 1)
				)
			)
		)
	)
	(symbol
		(lib_id "antmicropower:GND")
		(at 344.805 127 0)
		(unit 1)
		(exclude_from_sim no)
		(in_bom yes)
		(on_board yes)
		(dnp no)
		(fields_autoplaced yes)
		(property "Reference" "#PWR0165"
			(at 344.805 133.35 0)
			(effects
				(font
					(size 1.27 1.27)
				)
				(hide yes)
			)
		)
		(property "Value" "GND"
			(at 346.71 128.27 0)
			(effects
				(font
					(size 1.27 1.27)
					(thickness 0.15)
				)
				(justify left)
			)
		)
		(property "Footprint" ""
			(at 353.695 134.62 0)
			(effects
				(font
					(size 1.27 1.27)
					(thickness 0.15)
				)
				(justify left bottom)
				(hide yes)
			)
		)
		(property "Datasheet" ""
			(at 353.695 139.7 0)
			(effects
				(font
					(size 1.27 1.27)
					(thickness 0.15)
				)
				(justify left bottom)
				(hide yes)
			)
		)
		(property "Description" ""
			(at 353.695 142.24 0)
			(effects
				(font
					(size 1.27 1.27)
				)
				(justify left bottom)
				(hide yes)
			)
		)
		(property "Author" "Antmicro"
			(at 353.695 134.62 0)
			(effects
				(font
					(size 1.27 1.27)
					(thickness 0.15)
				)
				(justify left bottom)
				(hide yes)
			)
		)
		(property "License" "Apache-2.0"
			(at 353.695 137.16 0)
			(effects
				(font
					(size 1.27 1.27)
					(thickness 0.15)
				)
				(justify left bottom)
				(hide yes)
			)
		)
		(pin "1"
		)
		(instances
			(project "sodimm-ddr5-tester"
				(path ""
					(reference "#PWR0165")
					(unit 1)
				)
			)
		)
	)
	(symbol
		(lib_id "antmicropower:GND")
		(at 125.095 124.46 0)
		(unit 1)
		(exclude_from_sim no)
		(in_bom yes)
		(on_board yes)
		(dnp no)
		(fields_autoplaced yes)
		(property "Reference" "#PWR0126"
			(at 125.095 130.81 0)
			(effects
				(font
					(size 1.27 1.27)
				)
				(hide yes)
			)
		)
		(property "Value" "GND"
			(at 127 125.73 0)
			(effects
				(font
					(size 1.27 1.27)
					(thickness 0.15)
				)
				(justify left)
			)
		)
		(property "Footprint" ""
			(at 133.985 132.08 0)
			(effects
				(font
					(size 1.27 1.27)
					(thickness 0.15)
				)
				(justify left bottom)
				(hide yes)
			)
		)
		(property "Datasheet" ""
			(at 133.985 137.16 0)
			(effects
				(font
					(size 1.27 1.27)
					(thickness 0.15)
				)
				(justify left bottom)
				(hide yes)
			)
		)
		(property "Description" ""
			(at 133.985 139.7 0)
			(effects
				(font
					(size 1.27 1.27)
				)
				(justify left bottom)
				(hide yes)
			)
		)
		(property "Author" "Antmicro"
			(at 133.985 132.08 0)
			(effects
				(font
					(size 1.27 1.27)
					(thickness 0.15)
				)
				(justify left bottom)
				(hide yes)
			)
		)
		(property "License" "Apache-2.0"
			(at 133.985 134.62 0)
			(effects
				(font
					(size 1.27 1.27)
					(thickness 0.15)
				)
				(justify left bottom)
				(hide yes)
			)
		)
		(pin "1"
		)
		(instances
			(project "sodimm-ddr5-tester"
				(path ""
					(reference "#PWR0126")
					(unit 1)
				)
			)
		)
	)
	(symbol
		(lib_id "antmicroCapacitors0402:C_100n_0402")
		(at 59.055 247.65 90)
		(unit 1)
		(exclude_from_sim no)
		(in_bom yes)
		(on_board yes)
		(dnp no)
		(property "Reference" "C32"
			(at 59.69 243.205 90)
			(effects
				(font
					(size 1.27 1.27)
					(thickness 0.15)
				)
				(justify right)
			)
		)
		(property "Value" "C_100n_0402"
			(at 69.215 227.33 0)
			(effects
				(font
					(size 1.27 1.27)
					(thickness 0.15)
				)
				(justify left bottom)
				(hide yes)
			)
		)
		(property "Footprint" "antmicro-footprints:C_0402_1005Metric"
			(at 71.755 227.33 0)
			(effects
				(font
					(size 1.27 1.27)
					(thickness 0.15)
				)
				(justify left bottom)
				(hide yes)
			)
		)
		(property "Datasheet" "https://www.murata.com/products/productdetail?partno=GRM155R61H104KE14%23"
			(at 74.295 227.33 0)
			(effects
				(font
					(size 1.27 1.27)
					(thickness 0.15)
				)
				(justify left bottom)
				(hide yes)
			)
		)
		(property "Description" ""
			(at 59.055 247.65 0)
			(effects
				(font
					(size 1.27 1.27)
				)
			)
		)
		(property "MPN" "GRM155R61H104KE14D"
			(at 76.835 227.33 0)
			(effects
				(font
					(size 1.27 1.27)
					(thickness 0.15)
				)
				(justify left bottom)
				(hide yes)
			)
		)
		(property "Manufacturer" "Murata"
			(at 79.375 227.33 0)
			(effects
				(font
					(size 1.27 1.27)
					(thickness 0.15)
				)
				(justify left bottom)
				(hide yes)
			)
		)
		(property "License" "Apache-2.0"
			(at 81.915 227.33 0)
			(effects
				(font
					(size 1.27 1.27)
					(thickness 0.15)
				)
				(justify left bottom)
				(hide yes)
			)
		)
		(property "Author" "Antmicro"
			(at 84.455 227.33 0)
			(effects
				(font
					(size 1.27 1.27)
					(thickness 0.15)
				)
				(justify left bottom)
				(hide yes)
			)
		)
		(property "Val" "100n"
			(at 59.69 247.015 90)
			(effects
				(font
					(size 1.27 1.27)
					(thickness 0.15)
				)
				(justify right)
			)
		)
		(property "Voltage" "50V"
			(at 86.995 227.33 0)
			(effects
				(font
					(size 1.27 1.27)
				)
				(justify left bottom)
				(hide yes)
			)
		)
		(property "Dielectric" "X5R"
			(at 89.535 227.33 0)
			(effects
				(font
					(size 1.27 1.27)
				)
				(justify left bottom)
				(hide yes)
			)
		)
		(pin "1"
		)
		(pin "2"
		)
		(instances
			(project "sodimm-ddr5-tester"
				(path ""
					(reference "C32")
					(unit 1)
				)
			)
		)
	)
	(symbol
		(lib_id "antmicropower:GND")
		(at 158.115 162.56 0)
		(unit 1)
		(exclude_from_sim no)
		(in_bom yes)
		(on_board yes)
		(dnp no)
		(fields_autoplaced yes)
		(property "Reference" "#PWR096"
			(at 158.115 168.91 0)
			(effects
				(font
					(size 1.27 1.27)
				)
				(hide yes)
			)
		)
		(property "Value" "GND"
			(at 160.02 163.83 0)
			(effects
				(font
					(size 1.27 1.27)
					(thickness 0.15)
				)
				(justify left)
			)
		)
		(property "Footprint" ""
			(at 167.005 170.18 0)
			(effects
				(font
					(size 1.27 1.27)
					(thickness 0.15)
				)
				(justify left bottom)
				(hide yes)
			)
		)
		(property "Datasheet" ""
			(at 167.005 175.26 0)
			(effects
				(font
					(size 1.27 1.27)
					(thickness 0.15)
				)
				(justify left bottom)
				(hide yes)
			)
		)
		(property "Description" ""
			(at 167.005 177.8 0)
			(effects
				(font
					(size 1.27 1.27)
				)
				(justify left bottom)
				(hide yes)
			)
		)
		(property "Author" "Antmicro"
			(at 167.005 170.18 0)
			(effects
				(font
					(size 1.27 1.27)
					(thickness 0.15)
				)
				(justify left bottom)
				(hide yes)
			)
		)
		(property "License" "Apache-2.0"
			(at 167.005 172.72 0)
			(effects
				(font
					(size 1.27 1.27)
					(thickness 0.15)
				)
				(justify left bottom)
				(hide yes)
			)
		)
		(pin "1"
		)
		(instances
			(project "sodimm-ddr5-tester"
				(path ""
					(reference "#PWR096")
					(unit 1)
				)
			)
		)
	)
	(symbol
		(lib_id "antmicropower:+1V0_MGTAVCC")
		(at 331.47 53.34 0)
		(unit 1)
		(exclude_from_sim no)
		(in_bom yes)
		(on_board yes)
		(dnp no)
		(fields_autoplaced yes)
		(property "Reference" "#PWR0151"
			(at 331.47 57.15 0)
			(effects
				(font
					(size 1.27 1.27)
				)
				(hide yes)
			)
		)
		(property "Value" "+1V0_MGTAVCC"
			(at 331.47 49.53 0)
			(effects
				(font
					(size 1.27 1.27)
				)
			)
		)
		(property "Footprint" ""
			(at 331.47 53.34 0)
			(effects
				(font
					(size 1.27 1.27)
				)
				(hide yes)
			)
		)
		(property "Datasheet" ""
			(at 331.47 53.34 0)
			(effects
				(font
					(size 1.27 1.27)
				)
				(hide yes)
			)
		)
		(property "Description" ""
			(at 331.47 53.34 0)
			(effects
				(font
					(size 1.27 1.27)
				)
			)
		)
		(pin "1"
		)
		(instances
			(project "sodimm-ddr5-tester"
				(path ""
					(reference "#PWR0151")
					(unit 1)
				)
			)
		)
	)
	(symbol
		(lib_id "antmicroCapacitors0402:C_4u7_0402")
		(at 83.185 117.475 270)
		(unit 1)
		(exclude_from_sim no)
		(in_bom yes)
		(on_board yes)
		(dnp no)
		(property "Reference" "C50"
			(at 83.185 118.11 90)
			(effects
				(font
					(size 1.27 1.27)
				)
				(justify left)
			)
		)
		(property "Value" "C_4u7_0402"
			(at 73.025 137.795 0)
			(effects
				(font
					(size 1.27 1.27)
					(thickness 0.15)
				)
				(justify left bottom)
				(hide yes)
			)
		)
		(property "Footprint" "antmicro-footprints:C_0402_1005Metric"
			(at 70.485 137.795 0)
			(effects
				(font
					(size 1.27 1.27)
					(thickness 0.15)
				)
				(justify left bottom)
				(hide yes)
			)
		)
		(property "Datasheet" "https://www.murata.com/products/productdetail?partno=GRM155R61A475MEAA%23"
			(at 67.945 137.795 0)
			(effects
				(font
					(size 1.27 1.27)
					(thickness 0.15)
				)
				(justify left bottom)
				(hide yes)
			)
		)
		(property "Description" ""
			(at 83.185 117.475 0)
			(effects
				(font
					(size 1.27 1.27)
				)
			)
		)
		(property "Manufacturer" "Murata"
			(at 62.865 137.795 0)
			(effects
				(font
					(size 1.27 1.27)
					(thickness 0.15)
				)
				(justify left bottom)
				(hide yes)
			)
		)
		(property "MPN" "GRM155R61A475MEAAD"
			(at 65.405 137.795 0)
			(effects
				(font
					(size 1.27 1.27)
					(thickness 0.15)
				)
				(justify left bottom)
				(hide yes)
			)
		)
		(property "Val" "4u7"
			(at 83.185 121.92 90)
			(effects
				(font
					(size 1.27 1.27)
					(thickness 0.15)
				)
				(justify left)
			)
		)
		(property "License" "Apache-2.0"
			(at 60.325 137.795 0)
			(effects
				(font
					(size 1.27 1.27)
					(thickness 0.15)
				)
				(justify left bottom)
				(hide yes)
			)
		)
		(property "Author" "Antmicro"
			(at 57.785 137.795 0)
			(effects
				(font
					(size 1.27 1.27)
					(thickness 0.15)
				)
				(justify left bottom)
				(hide yes)
			)
		)
		(property "Voltage" ""
			(at 55.245 137.795 0)
			(effects
				(font
					(size 1.27 1.27)
				)
				(justify left bottom)
				(hide yes)
			)
		)
		(property "Dielectric" ""
			(at 52.705 137.795 0)
			(effects
				(font
					(size 1.27 1.27)
				)
				(justify left bottom)
				(hide yes)
			)
		)
		(pin "1"
		)
		(pin "2"
		)
		(instances
			(project "sodimm-ddr5-tester"
				(path ""
					(reference "C50")
					(unit 1)
				)
			)
		)
	)
	(symbol
		(lib_id "antmicroCapacitors0402:C_100n_0402")
		(at 137.16 189.23 90)
		(unit 1)
		(exclude_from_sim no)
		(in_bom yes)
		(on_board yes)
		(dnp no)
		(property "Reference" "C69"
			(at 137.795 184.785 90)
			(effects
				(font
					(size 1.27 1.27)
					(thickness 0.15)
				)
				(justify right)
			)
		)
		(property "Value" "C_100n_0402"
			(at 147.32 168.91 0)
			(effects
				(font
					(size 1.27 1.27)
					(thickness 0.15)
				)
				(justify left bottom)
				(hide yes)
			)
		)
		(property "Footprint" "antmicro-footprints:C_0402_1005Metric"
			(at 149.86 168.91 0)
			(effects
				(font
					(size 1.27 1.27)
					(thickness 0.15)
				)
				(justify left bottom)
				(hide yes)
			)
		)
		(property "Datasheet" "https://www.murata.com/products/productdetail?partno=GRM155R61H104KE14%23"
			(at 152.4 168.91 0)
			(effects
				(font
					(size 1.27 1.27)
					(thickness 0.15)
				)
				(justify left bottom)
				(hide yes)
			)
		)
		(property "Description" ""
			(at 137.16 189.23 0)
			(effects
				(font
					(size 1.27 1.27)
				)
			)
		)
		(property "MPN" "GRM155R61H104KE14D"
			(at 154.94 168.91 0)
			(effects
				(font
					(size 1.27 1.27)
					(thickness 0.15)
				)
				(justify left bottom)
				(hide yes)
			)
		)
		(property "Manufacturer" "Murata"
			(at 157.48 168.91 0)
			(effects
				(font
					(size 1.27 1.27)
					(thickness 0.15)
				)
				(justify left bottom)
				(hide yes)
			)
		)
		(property "License" "Apache-2.0"
			(at 160.02 168.91 0)
			(effects
				(font
					(size 1.27 1.27)
					(thickness 0.15)
				)
				(justify left bottom)
				(hide yes)
			)
		)
		(property "Author" "Antmicro"
			(at 162.56 168.91 0)
			(effects
				(font
					(size 1.27 1.27)
					(thickness 0.15)
				)
				(justify left bottom)
				(hide yes)
			)
		)
		(property "Val" "100n"
			(at 137.795 188.595 90)
			(effects
				(font
					(size 1.27 1.27)
					(thickness 0.15)
				)
				(justify right)
			)
		)
		(property "Voltage" "50V"
			(at 165.1 168.91 0)
			(effects
				(font
					(size 1.27 1.27)
				)
				(justify left bottom)
				(hide yes)
			)
		)
		(property "Dielectric" "X5R"
			(at 167.64 168.91 0)
			(effects
				(font
					(size 1.27 1.27)
				)
				(justify left bottom)
				(hide yes)
			)
		)
		(pin "1"
		)
		(pin "2"
		)
		(instances
			(project "sodimm-ddr5-tester"
				(path ""
					(reference "C69")
					(unit 1)
				)
			)
		)
	)
	(symbol
		(lib_id "antmicropower:GND")
		(at 147.32 94.615 0)
		(unit 1)
		(exclude_from_sim no)
		(in_bom yes)
		(on_board yes)
		(dnp no)
		(fields_autoplaced yes)
		(property "Reference" "#PWR0136"
			(at 147.32 100.965 0)
			(effects
				(font
					(size 1.27 1.27)
				)
				(hide yes)
			)
		)
		(property "Value" "GND"
			(at 149.86 95.885 0)
			(effects
				(font
					(size 1.27 1.27)
					(thickness 0.15)
				)
				(justify left)
			)
		)
		(property "Footprint" ""
			(at 156.21 102.235 0)
			(effects
				(font
					(size 1.27 1.27)
					(thickness 0.15)
				)
				(justify left bottom)
				(hide yes)
			)
		)
		(property "Datasheet" ""
			(at 156.21 107.315 0)
			(effects
				(font
					(size 1.27 1.27)
					(thickness 0.15)
				)
				(justify left bottom)
				(hide yes)
			)
		)
		(property "Description" ""
			(at 156.21 109.855 0)
			(effects
				(font
					(size 1.27 1.27)
				)
				(justify left bottom)
				(hide yes)
			)
		)
		(property "Author" "Antmicro"
			(at 156.21 102.235 0)
			(effects
				(font
					(size 1.27 1.27)
					(thickness 0.15)
				)
				(justify left bottom)
				(hide yes)
			)
		)
		(property "License" "Apache-2.0"
			(at 156.21 104.775 0)
			(effects
				(font
					(size 1.27 1.27)
					(thickness 0.15)
				)
				(justify left bottom)
				(hide yes)
			)
		)
		(pin "1"
		)
		(instances
			(project "sodimm-ddr5-tester"
				(path ""
					(reference "#PWR0136")
					(unit 1)
				)
			)
		)
	)
	(symbol
		(lib_id "antmicropower:+1V1")
		(at 116.205 151.765 0)
		(unit 1)
		(exclude_from_sim no)
		(in_bom yes)
		(on_board yes)
		(dnp no)
		(fields_autoplaced yes)
		(property "Reference" "#PWR057"
			(at 116.205 155.575 0)
			(effects
				(font
					(size 1.27 1.27)
				)
				(hide yes)
			)
		)
		(property "Value" "+1V1"
			(at 116.205 148.209 0)
			(effects
				(font
					(size 1.27 1.27)
				)
			)
		)
		(property "Footprint" ""
			(at 116.205 151.765 0)
			(effects
				(font
					(size 1.27 1.27)
				)
				(hide yes)
			)
		)
		(property "Datasheet" ""
			(at 116.205 151.765 0)
			(effects
				(font
					(size 1.27 1.27)
				)
				(hide yes)
			)
		)
		(property "Description" ""
			(at 116.205 151.765 0)
			(effects
				(font
					(size 1.27 1.27)
				)
			)
		)
		(pin "1"
		)
		(instances
			(project "sodimm-ddr5-tester"
				(path ""
					(reference "#PWR057")
					(unit 1)
				)
			)
		)
	)
	(symbol
		(lib_id "antmicroCapacitors0402:C_100n_0402")
		(at 158.115 160.655 90)
		(unit 1)
		(exclude_from_sim no)
		(in_bom yes)
		(on_board yes)
		(dnp no)
		(property "Reference" "C49"
			(at 158.75 156.21 90)
			(effects
				(font
					(size 1.27 1.27)
					(thickness 0.15)
				)
				(justify right)
			)
		)
		(property "Value" "C_100n_0402"
			(at 168.275 140.335 0)
			(effects
				(font
					(size 1.27 1.27)
					(thickness 0.15)
				)
				(justify left bottom)
				(hide yes)
			)
		)
		(property "Footprint" "antmicro-footprints:C_0402_1005Metric"
			(at 170.815 140.335 0)
			(effects
				(font
					(size 1.27 1.27)
					(thickness 0.15)
				)
				(justify left bottom)
				(hide yes)
			)
		)
		(property "Datasheet" "https://www.murata.com/products/productdetail?partno=GRM155R61H104KE14%23"
			(at 173.355 140.335 0)
			(effects
				(font
					(size 1.27 1.27)
					(thickness 0.15)
				)
				(justify left bottom)
				(hide yes)
			)
		)
		(property "Description" ""
			(at 158.115 160.655 0)
			(effects
				(font
					(size 1.27 1.27)
				)
			)
		)
		(property "MPN" "GRM155R61H104KE14D"
			(at 175.895 140.335 0)
			(effects
				(font
					(size 1.27 1.27)
					(thickness 0.15)
				)
				(justify left bottom)
				(hide yes)
			)
		)
		(property "Manufacturer" "Murata"
			(at 178.435 140.335 0)
			(effects
				(font
					(size 1.27 1.27)
					(thickness 0.15)
				)
				(justify left bottom)
				(hide yes)
			)
		)
		(property "License" "Apache-2.0"
			(at 180.975 140.335 0)
			(effects
				(font
					(size 1.27 1.27)
					(thickness 0.15)
				)
				(justify left bottom)
				(hide yes)
			)
		)
		(property "Author" "Antmicro"
			(at 183.515 140.335 0)
			(effects
				(font
					(size 1.27 1.27)
					(thickness 0.15)
				)
				(justify left bottom)
				(hide yes)
			)
		)
		(property "Val" "100n"
			(at 158.75 160.02 90)
			(effects
				(font
					(size 1.27 1.27)
					(thickness 0.15)
				)
				(justify right)
			)
		)
		(property "Voltage" "50V"
			(at 186.055 140.335 0)
			(effects
				(font
					(size 1.27 1.27)
				)
				(justify left bottom)
				(hide yes)
			)
		)
		(property "Dielectric" "X5R"
			(at 188.595 140.335 0)
			(effects
				(font
					(size 1.27 1.27)
				)
				(justify left bottom)
				(hide yes)
			)
		)
		(pin "1"
		)
		(pin "2"
		)
		(instances
			(project "sodimm-ddr5-tester"
				(path ""
					(reference "C49")
					(unit 1)
				)
			)
		)
	)
	(symbol
		(lib_id "antmicropower:GND")
		(at 339.725 63.5 0)
		(unit 1)
		(exclude_from_sim no)
		(in_bom yes)
		(on_board yes)
		(dnp no)
		(fields_autoplaced yes)
		(property "Reference" "#PWR0152"
			(at 339.725 69.85 0)
			(effects
				(font
					(size 1.27 1.27)
				)
				(hide yes)
			)
		)
		(property "Value" "GND"
			(at 341.63 64.77 0)
			(effects
				(font
					(size 1.27 1.27)
					(thickness 0.15)
				)
				(justify left)
			)
		)
		(property "Footprint" ""
			(at 348.615 71.12 0)
			(effects
				(font
					(size 1.27 1.27)
					(thickness 0.15)
				)
				(justify left bottom)
				(hide yes)
			)
		)
		(property "Datasheet" ""
			(at 348.615 76.2 0)
			(effects
				(font
					(size 1.27 1.27)
					(thickness 0.15)
				)
				(justify left bottom)
				(hide yes)
			)
		)
		(property "Description" ""
			(at 348.615 78.74 0)
			(effects
				(font
					(size 1.27 1.27)
				)
				(justify left bottom)
				(hide yes)
			)
		)
		(property "Author" "Antmicro"
			(at 348.615 71.12 0)
			(effects
				(font
					(size 1.27 1.27)
					(thickness 0.15)
				)
				(justify left bottom)
				(hide yes)
			)
		)
		(property "License" "Apache-2.0"
			(at 348.615 73.66 0)
			(effects
				(font
					(size 1.27 1.27)
					(thickness 0.15)
				)
				(justify left bottom)
				(hide yes)
			)
		)
		(pin "1"
		)
		(instances
			(project "sodimm-ddr5-tester"
				(path ""
					(reference "#PWR0152")
					(unit 1)
				)
			)
		)
	)
	(symbol
		(lib_id "antmicroCapacitors0402:C_100n_0402")
		(at 122.555 93.345 90)
		(unit 1)
		(exclude_from_sim no)
		(in_bom yes)
		(on_board yes)
		(dnp no)
		(property "Reference" "C75"
			(at 123.19 88.9 90)
			(effects
				(font
					(size 1.27 1.27)
					(thickness 0.15)
				)
				(justify right)
			)
		)
		(property "Value" "C_100n_0402"
			(at 132.715 73.025 0)
			(effects
				(font
					(size 1.27 1.27)
					(thickness 0.15)
				)
				(justify left bottom)
				(hide yes)
			)
		)
		(property "Footprint" "antmicro-footprints:C_0402_1005Metric"
			(at 135.255 73.025 0)
			(effects
				(font
					(size 1.27 1.27)
					(thickness 0.15)
				)
				(justify left bottom)
				(hide yes)
			)
		)
		(property "Datasheet" "https://www.murata.com/products/productdetail?partno=GRM155R61H104KE14%23"
			(at 137.795 73.025 0)
			(effects
				(font
					(size 1.27 1.27)
					(thickness 0.15)
				)
				(justify left bottom)
				(hide yes)
			)
		)
		(property "Description" ""
			(at 122.555 93.345 0)
			(effects
				(font
					(size 1.27 1.27)
				)
			)
		)
		(property "MPN" "GRM155R61H104KE14D"
			(at 140.335 73.025 0)
			(effects
				(font
					(size 1.27 1.27)
					(thickness 0.15)
				)
				(justify left bottom)
				(hide yes)
			)
		)
		(property "Manufacturer" "Murata"
			(at 142.875 73.025 0)
			(effects
				(font
					(size 1.27 1.27)
					(thickness 0.15)
				)
				(justify left bottom)
				(hide yes)
			)
		)
		(property "License" "Apache-2.0"
			(at 145.415 73.025 0)
			(effects
				(font
					(size 1.27 1.27)
					(thickness 0.15)
				)
				(justify left bottom)
				(hide yes)
			)
		)
		(property "Author" "Antmicro"
			(at 147.955 73.025 0)
			(effects
				(font
					(size 1.27 1.27)
					(thickness 0.15)
				)
				(justify left bottom)
				(hide yes)
			)
		)
		(property "Val" "100n"
			(at 123.19 92.71 90)
			(effects
				(font
					(size 1.27 1.27)
					(thickness 0.15)
				)
				(justify right)
			)
		)
		(property "Voltage" "50V"
			(at 150.495 73.025 0)
			(effects
				(font
					(size 1.27 1.27)
				)
				(justify left bottom)
				(hide yes)
			)
		)
		(property "Dielectric" "X5R"
			(at 153.035 73.025 0)
			(effects
				(font
					(size 1.27 1.27)
				)
				(justify left bottom)
				(hide yes)
			)
		)
		(pin "1"
		)
		(pin "2"
		)
		(instances
			(project "sodimm-ddr5-tester"
				(path ""
					(reference "C75")
					(unit 1)
				)
			)
		)
	)
	(symbol
		(lib_id "antmicroCapacitors0402:C_100n_0402")
		(at 45.72 219.71 90)
		(unit 1)
		(exclude_from_sim no)
		(in_bom yes)
		(on_board yes)
		(dnp no)
		(property "Reference" "C23"
			(at 50.165 215.265 90)
			(effects
				(font
					(size 1.27 1.27)
					(thickness 0.15)
				)
				(justify left)
			)
		)
		(property "Value" "C_100n_0402"
			(at 55.88 199.39 0)
			(effects
				(font
					(size 1.27 1.27)
					(thickness 0.15)
				)
				(justify left bottom)
				(hide yes)
			)
		)
		(property "Footprint" "antmicro-footprints:C_0402_1005Metric"
			(at 58.42 199.39 0)
			(effects
				(font
					(size 1.27 1.27)
					(thickness 0.15)
				)
				(justify left bottom)
				(hide yes)
			)
		)
		(property "Datasheet" "https://www.murata.com/products/productdetail?partno=GRM155R61H104KE14%23"
			(at 60.96 199.39 0)
			(effects
				(font
					(size 1.27 1.27)
					(thickness 0.15)
				)
				(justify left bottom)
				(hide yes)
			)
		)
		(property "Description" ""
			(at 45.72 219.71 0)
			(effects
				(font
					(size 1.27 1.27)
				)
			)
		)
		(property "MPN" "GRM155R61H104KE14D"
			(at 63.5 199.39 0)
			(effects
				(font
					(size 1.27 1.27)
					(thickness 0.15)
				)
				(justify left bottom)
				(hide yes)
			)
		)
		(property "Manufacturer" "Murata"
			(at 66.04 199.39 0)
			(effects
				(font
					(size 1.27 1.27)
					(thickness 0.15)
				)
				(justify left bottom)
				(hide yes)
			)
		)
		(property "License" "Apache-2.0"
			(at 68.58 199.39 0)
			(effects
				(font
					(size 1.27 1.27)
					(thickness 0.15)
				)
				(justify left bottom)
				(hide yes)
			)
		)
		(property "Author" "Antmicro"
			(at 71.12 199.39 0)
			(effects
				(font
					(size 1.27 1.27)
					(thickness 0.15)
				)
				(justify left bottom)
				(hide yes)
			)
		)
		(property "Val" "100n"
			(at 51.435 219.075 90)
			(effects
				(font
					(size 1.27 1.27)
					(thickness 0.15)
				)
				(justify left)
			)
		)
		(property "Voltage" "50V"
			(at 73.66 199.39 0)
			(effects
				(font
					(size 1.27 1.27)
				)
				(justify left bottom)
				(hide yes)
			)
		)
		(property "Dielectric" "X5R"
			(at 76.2 199.39 0)
			(effects
				(font
					(size 1.27 1.27)
				)
				(justify left bottom)
				(hide yes)
			)
		)
		(pin "1"
		)
		(pin "2"
		)
		(instances
			(project "sodimm-ddr5-tester"
				(path ""
					(reference "C23")
					(unit 1)
				)
			)
		)
	)
	(symbol
		(lib_id "antmicroCapacitors0402:C_100n_0402")
		(at 344.805 125.73 90)
		(unit 1)
		(exclude_from_sim no)
		(in_bom yes)
		(on_board yes)
		(dnp no)
		(property "Reference" "C105"
			(at 345.44 121.285 90)
			(effects
				(font
					(size 1.27 1.27)
					(thickness 0.15)
				)
				(justify right)
			)
		)
		(property "Value" "C_100n_0402"
			(at 354.965 105.41 0)
			(effects
				(font
					(size 1.27 1.27)
					(thickness 0.15)
				)
				(justify left bottom)
				(hide yes)
			)
		)
		(property "Footprint" "antmicro-footprints:C_0402_1005Metric"
			(at 357.505 105.41 0)
			(effects
				(font
					(size 1.27 1.27)
					(thickness 0.15)
				)
				(justify left bottom)
				(hide yes)
			)
		)
		(property "Datasheet" "https://www.murata.com/products/productdetail?partno=GRM155R61H104KE14%23"
			(at 360.045 105.41 0)
			(effects
				(font
					(size 1.27 1.27)
					(thickness 0.15)
				)
				(justify left bottom)
				(hide yes)
			)
		)
		(property "Description" ""
			(at 344.805 125.73 0)
			(effects
				(font
					(size 1.27 1.27)
				)
			)
		)
		(property "MPN" "GRM155R61H104KE14D"
			(at 362.585 105.41 0)
			(effects
				(font
					(size 1.27 1.27)
					(thickness 0.15)
				)
				(justify left bottom)
				(hide yes)
			)
		)
		(property "Manufacturer" "Murata"
			(at 365.125 105.41 0)
			(effects
				(font
					(size 1.27 1.27)
					(thickness 0.15)
				)
				(justify left bottom)
				(hide yes)
			)
		)
		(property "License" "Apache-2.0"
			(at 367.665 105.41 0)
			(effects
				(font
					(size 1.27 1.27)
					(thickness 0.15)
				)
				(justify left bottom)
				(hide yes)
			)
		)
		(property "Author" "Antmicro"
			(at 370.205 105.41 0)
			(effects
				(font
					(size 1.27 1.27)
					(thickness 0.15)
				)
				(justify left bottom)
				(hide yes)
			)
		)
		(property "Val" "100n"
			(at 345.44 125.095 90)
			(effects
				(font
					(size 1.27 1.27)
					(thickness 0.15)
				)
				(justify right)
			)
		)
		(property "Voltage" "50V"
			(at 372.745 105.41 0)
			(effects
				(font
					(size 1.27 1.27)
				)
				(justify left bottom)
				(hide yes)
			)
		)
		(property "Dielectric" "X5R"
			(at 375.285 105.41 0)
			(effects
				(font
					(size 1.27 1.27)
				)
				(justify left bottom)
				(hide yes)
			)
		)
		(pin "1"
		)
		(pin "2"
		)
		(instances
			(project "sodimm-ddr5-tester"
				(path ""
					(reference "C105")
					(unit 1)
				)
			)
		)
	)
	(symbol
		(lib_id "antmicropower:GND")
		(at 59.055 248.92 0)
		(unit 1)
		(exclude_from_sim no)
		(in_bom yes)
		(on_board yes)
		(dnp no)
		(fields_autoplaced yes)
		(property "Reference" "#PWR079"
			(at 59.055 255.27 0)
			(effects
				(font
					(size 1.27 1.27)
				)
				(hide yes)
			)
		)
		(property "Value" "GND"
			(at 60.96 250.19 0)
			(effects
				(font
					(size 1.27 1.27)
					(thickness 0.15)
				)
				(justify left)
			)
		)
		(property "Footprint" ""
			(at 67.945 256.54 0)
			(effects
				(font
					(size 1.27 1.27)
					(thickness 0.15)
				)
				(justify left bottom)
				(hide yes)
			)
		)
		(property "Datasheet" ""
			(at 67.945 261.62 0)
			(effects
				(font
					(size 1.27 1.27)
					(thickness 0.15)
				)
				(justify left bottom)
				(hide yes)
			)
		)
		(property "Description" ""
			(at 67.945 264.16 0)
			(effects
				(font
					(size 1.27 1.27)
				)
				(justify left bottom)
				(hide yes)
			)
		)
		(property "Author" "Antmicro"
			(at 67.945 256.54 0)
			(effects
				(font
					(size 1.27 1.27)
					(thickness 0.15)
				)
				(justify left bottom)
				(hide yes)
			)
		)
		(property "License" "Apache-2.0"
			(at 67.945 259.08 0)
			(effects
				(font
					(size 1.27 1.27)
					(thickness 0.15)
				)
				(justify left bottom)
				(hide yes)
			)
		)
		(pin "1"
		)
		(instances
			(project "sodimm-ddr5-tester"
				(path ""
					(reference "#PWR079")
					(unit 1)
				)
			)
		)
	)
	(symbol
		(lib_id "antmicroCapacitors0402:C_100n_0402")
		(at 352.425 125.73 90)
		(unit 1)
		(exclude_from_sim no)
		(in_bom yes)
		(on_board yes)
		(dnp no)
		(property "Reference" "C106"
			(at 353.06 121.285 90)
			(effects
				(font
					(size 1.27 1.27)
					(thickness 0.15)
				)
				(justify right)
			)
		)
		(property "Value" "C_100n_0402"
			(at 362.585 105.41 0)
			(effects
				(font
					(size 1.27 1.27)
					(thickness 0.15)
				)
				(justify left bottom)
				(hide yes)
			)
		)
		(property "Footprint" "antmicro-footprints:C_0402_1005Metric"
			(at 365.125 105.41 0)
			(effects
				(font
					(size 1.27 1.27)
					(thickness 0.15)
				)
				(justify left bottom)
				(hide yes)
			)
		)
		(property "Datasheet" "https://www.murata.com/products/productdetail?partno=GRM155R61H104KE14%23"
			(at 367.665 105.41 0)
			(effects
				(font
					(size 1.27 1.27)
					(thickness 0.15)
				)
				(justify left bottom)
				(hide yes)
			)
		)
		(property "Description" ""
			(at 352.425 125.73 0)
			(effects
				(font
					(size 1.27 1.27)
				)
			)
		)
		(property "MPN" "GRM155R61H104KE14D"
			(at 370.205 105.41 0)
			(effects
				(font
					(size 1.27 1.27)
					(thickness 0.15)
				)
				(justify left bottom)
				(hide yes)
			)
		)
		(property "Manufacturer" "Murata"
			(at 372.745 105.41 0)
			(effects
				(font
					(size 1.27 1.27)
					(thickness 0.15)
				)
				(justify left bottom)
				(hide yes)
			)
		)
		(property "License" "Apache-2.0"
			(at 375.285 105.41 0)
			(effects
				(font
					(size 1.27 1.27)
					(thickness 0.15)
				)
				(justify left bottom)
				(hide yes)
			)
		)
		(property "Author" "Antmicro"
			(at 377.825 105.41 0)
			(effects
				(font
					(size 1.27 1.27)
					(thickness 0.15)
				)
				(justify left bottom)
				(hide yes)
			)
		)
		(property "Val" "100n"
			(at 353.06 125.095 90)
			(effects
				(font
					(size 1.27 1.27)
					(thickness 0.15)
				)
				(justify right)
			)
		)
		(property "Voltage" "50V"
			(at 380.365 105.41 0)
			(effects
				(font
					(size 1.27 1.27)
				)
				(justify left bottom)
				(hide yes)
			)
		)
		(property "Dielectric" "X5R"
			(at 382.905 105.41 0)
			(effects
				(font
					(size 1.27 1.27)
				)
				(justify left bottom)
				(hide yes)
			)
		)
		(pin "1"
		)
		(pin "2"
		)
		(instances
			(project "sodimm-ddr5-tester"
				(path ""
					(reference "C106")
					(unit 1)
				)
			)
		)
	)
	(symbol
		(lib_id "antmicropower:GND")
		(at 157.48 222.25 0)
		(unit 1)
		(exclude_from_sim no)
		(in_bom yes)
		(on_board yes)
		(dnp no)
		(fields_autoplaced yes)
		(property "Reference" "#PWR0145"
			(at 157.48 228.6 0)
			(effects
				(font
					(size 1.27 1.27)
				)
				(hide yes)
			)
		)
		(property "Value" "GND"
			(at 160.02 223.52 0)
			(effects
				(font
					(size 1.27 1.27)
					(thickness 0.15)
				)
				(justify left)
			)
		)
		(property "Footprint" ""
			(at 166.37 229.87 0)
			(effects
				(font
					(size 1.27 1.27)
					(thickness 0.15)
				)
				(justify left bottom)
				(hide yes)
			)
		)
		(property "Datasheet" ""
			(at 166.37 234.95 0)
			(effects
				(font
					(size 1.27 1.27)
					(thickness 0.15)
				)
				(justify left bottom)
				(hide yes)
			)
		)
		(property "Description" ""
			(at 166.37 237.49 0)
			(effects
				(font
					(size 1.27 1.27)
				)
				(justify left bottom)
				(hide yes)
			)
		)
		(property "Author" "Antmicro"
			(at 166.37 229.87 0)
			(effects
				(font
					(size 1.27 1.27)
					(thickness 0.15)
				)
				(justify left bottom)
				(hide yes)
			)
		)
		(property "License" "Apache-2.0"
			(at 166.37 232.41 0)
			(effects
				(font
					(size 1.27 1.27)
					(thickness 0.15)
				)
				(justify left bottom)
				(hide yes)
			)
		)
		(pin "1"
		)
		(instances
			(project "sodimm-ddr5-tester"
				(path ""
					(reference "#PWR0145")
					(unit 1)
				)
			)
		)
	)
	(symbol
		(lib_id "antmicroCapacitors0402:C_100n_0402")
		(at 143.51 220.345 90)
		(unit 1)
		(exclude_from_sim no)
		(in_bom yes)
		(on_board yes)
		(dnp no)
		(property "Reference" "C93"
			(at 144.145 215.9 90)
			(effects
				(font
					(size 1.27 1.27)
					(thickness 0.15)
				)
				(justify right)
			)
		)
		(property "Value" "C_100n_0402"
			(at 153.67 200.025 0)
			(effects
				(font
					(size 1.27 1.27)
					(thickness 0.15)
				)
				(justify left bottom)
				(hide yes)
			)
		)
		(property "Footprint" "antmicro-footprints:C_0402_1005Metric"
			(at 156.21 200.025 0)
			(effects
				(font
					(size 1.27 1.27)
					(thickness 0.15)
				)
				(justify left bottom)
				(hide yes)
			)
		)
		(property "Datasheet" "https://www.murata.com/products/productdetail?partno=GRM155R61H104KE14%23"
			(at 158.75 200.025 0)
			(effects
				(font
					(size 1.27 1.27)
					(thickness 0.15)
				)
				(justify left bottom)
				(hide yes)
			)
		)
		(property "Description" ""
			(at 143.51 220.345 0)
			(effects
				(font
					(size 1.27 1.27)
				)
			)
		)
		(property "MPN" "GRM155R61H104KE14D"
			(at 161.29 200.025 0)
			(effects
				(font
					(size 1.27 1.27)
					(thickness 0.15)
				)
				(justify left bottom)
				(hide yes)
			)
		)
		(property "Manufacturer" "Murata"
			(at 163.83 200.025 0)
			(effects
				(font
					(size 1.27 1.27)
					(thickness 0.15)
				)
				(justify left bottom)
				(hide yes)
			)
		)
		(property "License" "Apache-2.0"
			(at 166.37 200.025 0)
			(effects
				(font
					(size 1.27 1.27)
					(thickness 0.15)
				)
				(justify left bottom)
				(hide yes)
			)
		)
		(property "Author" "Antmicro"
			(at 168.91 200.025 0)
			(effects
				(font
					(size 1.27 1.27)
					(thickness 0.15)
				)
				(justify left bottom)
				(hide yes)
			)
		)
		(property "Val" "100n"
			(at 144.145 219.71 90)
			(effects
				(font
					(size 1.27 1.27)
					(thickness 0.15)
				)
				(justify right)
			)
		)
		(property "Voltage" "50V"
			(at 171.45 200.025 0)
			(effects
				(font
					(size 1.27 1.27)
				)
				(justify left bottom)
				(hide yes)
			)
		)
		(property "Dielectric" "X5R"
			(at 173.99 200.025 0)
			(effects
				(font
					(size 1.27 1.27)
				)
				(justify left bottom)
				(hide yes)
			)
		)
		(pin "1"
		)
		(pin "2"
		)
		(instances
			(project "sodimm-ddr5-tester"
				(path ""
					(reference "C93")
					(unit 1)
				)
			)
		)
	)
	(symbol
		(lib_id "antmicropower:GND")
		(at 163.83 94.615 0)
		(unit 1)
		(exclude_from_sim no)
		(in_bom yes)
		(on_board yes)
		(dnp no)
		(fields_autoplaced yes)
		(property "Reference" "#PWR0140"
			(at 163.83 100.965 0)
			(effects
				(font
					(size 1.27 1.27)
				)
				(hide yes)
			)
		)
		(property "Value" "GND"
			(at 166.37 95.885 0)
			(effects
				(font
					(size 1.27 1.27)
					(thickness 0.15)
				)
				(justify left)
			)
		)
		(property "Footprint" ""
			(at 172.72 102.235 0)
			(effects
				(font
					(size 1.27 1.27)
					(thickness 0.15)
				)
				(justify left bottom)
				(hide yes)
			)
		)
		(property "Datasheet" ""
			(at 172.72 107.315 0)
			(effects
				(font
					(size 1.27 1.27)
					(thickness 0.15)
				)
				(justify left bottom)
				(hide yes)
			)
		)
		(property "Description" ""
			(at 172.72 109.855 0)
			(effects
				(font
					(size 1.27 1.27)
				)
				(justify left bottom)
				(hide yes)
			)
		)
		(property "Author" "Antmicro"
			(at 172.72 102.235 0)
			(effects
				(font
					(size 1.27 1.27)
					(thickness 0.15)
				)
				(justify left bottom)
				(hide yes)
			)
		)
		(property "License" "Apache-2.0"
			(at 172.72 104.775 0)
			(effects
				(font
					(size 1.27 1.27)
					(thickness 0.15)
				)
				(justify left bottom)
				(hide yes)
			)
		)
		(pin "1"
		)
		(instances
			(project "sodimm-ddr5-tester"
				(path ""
					(reference "#PWR0140")
					(unit 1)
				)
			)
		)
	)
	(symbol
		(lib_id "antmicroCapacitors0402:C_4u7_0402")
		(at 330.2 120.65 270)
		(unit 1)
		(exclude_from_sim no)
		(in_bom yes)
		(on_board yes)
		(dnp no)
		(property "Reference" "C103"
			(at 330.2 120.65 90)
			(effects
				(font
					(size 1.27 1.27)
				)
				(justify left)
			)
		)
		(property "Value" "C_4u7_0402"
			(at 320.04 140.97 0)
			(effects
				(font
					(size 1.27 1.27)
					(thickness 0.15)
				)
				(justify left bottom)
				(hide yes)
			)
		)
		(property "Footprint" "antmicro-footprints:C_0402_1005Metric"
			(at 317.5 140.97 0)
			(effects
				(font
					(size 1.27 1.27)
					(thickness 0.15)
				)
				(justify left bottom)
				(hide yes)
			)
		)
		(property "Datasheet" "https://www.murata.com/products/productdetail?partno=GRM155R61A475MEAA%23"
			(at 314.96 140.97 0)
			(effects
				(font
					(size 1.27 1.27)
					(thickness 0.15)
				)
				(justify left bottom)
				(hide yes)
			)
		)
		(property "Description" ""
			(at 330.2 120.65 0)
			(effects
				(font
					(size 1.27 1.27)
				)
			)
		)
		(property "Manufacturer" "Murata"
			(at 309.88 140.97 0)
			(effects
				(font
					(size 1.27 1.27)
					(thickness 0.15)
				)
				(justify left bottom)
				(hide yes)
			)
		)
		(property "MPN" "GRM155R61A475MEAAD"
			(at 312.42 140.97 0)
			(effects
				(font
					(size 1.27 1.27)
					(thickness 0.15)
				)
				(justify left bottom)
				(hide yes)
			)
		)
		(property "Val" "4u7"
			(at 330.835 125.095 90)
			(effects
				(font
					(size 1.27 1.27)
					(thickness 0.15)
				)
				(justify left)
			)
		)
		(property "License" "Apache-2.0"
			(at 307.34 140.97 0)
			(effects
				(font
					(size 1.27 1.27)
					(thickness 0.15)
				)
				(justify left bottom)
				(hide yes)
			)
		)
		(property "Author" "Antmicro"
			(at 304.8 140.97 0)
			(effects
				(font
					(size 1.27 1.27)
					(thickness 0.15)
				)
				(justify left bottom)
				(hide yes)
			)
		)
		(property "Voltage" ""
			(at 302.26 140.97 0)
			(effects
				(font
					(size 1.27 1.27)
				)
				(justify left bottom)
				(hide yes)
			)
		)
		(property "Dielectric" ""
			(at 299.72 140.97 0)
			(effects
				(font
					(size 1.27 1.27)
				)
				(justify left bottom)
				(hide yes)
			)
		)
		(pin "1"
		)
		(pin "2"
		)
		(instances
			(project "sodimm-ddr5-tester"
				(path ""
					(reference "C103")
					(unit 1)
				)
			)
		)
	)
	(symbol
		(lib_id "antmicroCapacitors0402:C_4u7_0402")
		(at 340.995 89.535 270)
		(unit 1)
		(exclude_from_sim no)
		(in_bom yes)
		(on_board yes)
		(dnp no)
		(property "Reference" "C97"
			(at 341.63 89.535 90)
			(effects
				(font
					(size 1.27 1.27)
				)
				(justify left)
			)
		)
		(property "Value" "C_4u7_0402"
			(at 330.835 109.855 0)
			(effects
				(font
					(size 1.27 1.27)
					(thickness 0.15)
				)
				(justify left bottom)
				(hide yes)
			)
		)
		(property "Footprint" "antmicro-footprints:C_0402_1005Metric"
			(at 328.295 109.855 0)
			(effects
				(font
					(size 1.27 1.27)
					(thickness 0.15)
				)
				(justify left bottom)
				(hide yes)
			)
		)
		(property "Datasheet" "https://www.murata.com/products/productdetail?partno=GRM155R61A475MEAA%23"
			(at 325.755 109.855 0)
			(effects
				(font
					(size 1.27 1.27)
					(thickness 0.15)
				)
				(justify left bottom)
				(hide yes)
			)
		)
		(property "Description" ""
			(at 340.995 89.535 0)
			(effects
				(font
					(size 1.27 1.27)
				)
			)
		)
		(property "Manufacturer" "Murata"
			(at 320.675 109.855 0)
			(effects
				(font
					(size 1.27 1.27)
					(thickness 0.15)
				)
				(justify left bottom)
				(hide yes)
			)
		)
		(property "MPN" "GRM155R61A475MEAAD"
			(at 323.215 109.855 0)
			(effects
				(font
					(size 1.27 1.27)
					(thickness 0.15)
				)
				(justify left bottom)
				(hide yes)
			)
		)
		(property "Val" "4u7"
			(at 343.535 93.9862 90)
			(effects
				(font
					(size 1.27 1.27)
					(thickness 0.15)
				)
				(justify left)
			)
		)
		(property "License" "Apache-2.0"
			(at 318.135 109.855 0)
			(effects
				(font
					(size 1.27 1.27)
					(thickness 0.15)
				)
				(justify left bottom)
				(hide yes)
			)
		)
		(property "Author" "Antmicro"
			(at 315.595 109.855 0)
			(effects
				(font
					(size 1.27 1.27)
					(thickness 0.15)
				)
				(justify left bottom)
				(hide yes)
			)
		)
		(property "Voltage" ""
			(at 313.055 109.855 0)
			(effects
				(font
					(size 1.27 1.27)
				)
				(justify left bottom)
				(hide yes)
			)
		)
		(property "Dielectric" ""
			(at 310.515 109.855 0)
			(effects
				(font
					(size 1.27 1.27)
				)
				(justify left bottom)
				(hide yes)
			)
		)
		(pin "1"
		)
		(pin "2"
		)
		(instances
			(project "sodimm-ddr5-tester"
				(path ""
					(reference "C97")
					(unit 1)
				)
			)
		)
	)
	(symbol
		(lib_id "antmicroCapacitors0402:C_100n_0402")
		(at 45.72 160.02 90)
		(unit 1)
		(exclude_from_sim no)
		(in_bom yes)
		(on_board yes)
		(dnp no)
		(property "Reference" "C76"
			(at 50.165 155.575 90)
			(effects
				(font
					(size 1.27 1.27)
					(thickness 0.15)
				)
				(justify left)
			)
		)
		(property "Value" "C_100n_0402"
			(at 55.88 139.7 0)
			(effects
				(font
					(size 1.27 1.27)
					(thickness 0.15)
				)
				(justify left bottom)
				(hide yes)
			)
		)
		(property "Footprint" "antmicro-footprints:C_0402_1005Metric"
			(at 58.42 139.7 0)
			(effects
				(font
					(size 1.27 1.27)
					(thickness 0.15)
				)
				(justify left bottom)
				(hide yes)
			)
		)
		(property "Datasheet" "https://www.murata.com/products/productdetail?partno=GRM155R61H104KE14%23"
			(at 60.96 139.7 0)
			(effects
				(font
					(size 1.27 1.27)
					(thickness 0.15)
				)
				(justify left bottom)
				(hide yes)
			)
		)
		(property "Description" ""
			(at 45.72 160.02 0)
			(effects
				(font
					(size 1.27 1.27)
				)
			)
		)
		(property "MPN" "GRM155R61H104KE14D"
			(at 63.5 139.7 0)
			(effects
				(font
					(size 1.27 1.27)
					(thickness 0.15)
				)
				(justify left bottom)
				(hide yes)
			)
		)
		(property "Manufacturer" "Murata"
			(at 66.04 139.7 0)
			(effects
				(font
					(size 1.27 1.27)
					(thickness 0.15)
				)
				(justify left bottom)
				(hide yes)
			)
		)
		(property "License" "Apache-2.0"
			(at 68.58 139.7 0)
			(effects
				(font
					(size 1.27 1.27)
					(thickness 0.15)
				)
				(justify left bottom)
				(hide yes)
			)
		)
		(property "Author" "Antmicro"
			(at 71.12 139.7 0)
			(effects
				(font
					(size 1.27 1.27)
					(thickness 0.15)
				)
				(justify left bottom)
				(hide yes)
			)
		)
		(property "Val" "100n"
			(at 51.435 159.385 90)
			(effects
				(font
					(size 1.27 1.27)
					(thickness 0.15)
				)
				(justify left)
			)
		)
		(property "Voltage" "50V"
			(at 73.66 139.7 0)
			(effects
				(font
					(size 1.27 1.27)
				)
				(justify left bottom)
				(hide yes)
			)
		)
		(property "Dielectric" "X5R"
			(at 76.2 139.7 0)
			(effects
				(font
					(size 1.27 1.27)
				)
				(justify left bottom)
				(hide yes)
			)
		)
		(pin "1"
		)
		(pin "2"
		)
		(instances
			(project "sodimm-ddr5-tester"
				(path ""
					(reference "C76")
					(unit 1)
				)
			)
		)
	)
	(symbol
		(lib_id "antmicropower:GND")
		(at 111.76 68.58 0)
		(mirror y)
		(unit 1)
		(exclude_from_sim no)
		(in_bom yes)
		(on_board yes)
		(dnp no)
		(fields_autoplaced yes)
		(property "Reference" "#PWR0110"
			(at 111.76 74.93 0)
			(effects
				(font
					(size 1.27 1.27)
				)
				(hide yes)
			)
		)
		(property "Value" "GND"
			(at 114.3 69.85 0)
			(effects
				(font
					(size 1.27 1.27)
					(thickness 0.15)
				)
				(justify right)
			)
		)
		(property "Footprint" ""
			(at 102.87 76.2 0)
			(effects
				(font
					(size 1.27 1.27)
					(thickness 0.15)
				)
				(justify left bottom)
				(hide yes)
			)
		)
		(property "Datasheet" ""
			(at 102.87 81.28 0)
			(effects
				(font
					(size 1.27 1.27)
					(thickness 0.15)
				)
				(justify left bottom)
				(hide yes)
			)
		)
		(property "Description" ""
			(at 102.87 83.82 0)
			(effects
				(font
					(size 1.27 1.27)
				)
				(justify left bottom)
				(hide yes)
			)
		)
		(property "Author" "Antmicro"
			(at 102.87 76.2 0)
			(effects
				(font
					(size 1.27 1.27)
					(thickness 0.15)
				)
				(justify left bottom)
				(hide yes)
			)
		)
		(property "License" "Apache-2.0"
			(at 102.87 78.74 0)
			(effects
				(font
					(size 1.27 1.27)
					(thickness 0.15)
				)
				(justify left bottom)
				(hide yes)
			)
		)
		(pin "1"
		)
		(instances
			(project "sodimm-ddr5-tester"
				(path ""
					(reference "#PWR0110")
					(unit 1)
				)
			)
		)
	)
	(symbol
		(lib_id "antmicroCapacitors0402:C_100n_0402")
		(at 359.41 125.73 90)
		(unit 1)
		(exclude_from_sim no)
		(in_bom yes)
		(on_board yes)
		(dnp no)
		(property "Reference" "C107"
			(at 360.045 121.285 90)
			(effects
				(font
					(size 1.27 1.27)
					(thickness 0.15)
				)
				(justify right)
			)
		)
		(property "Value" "C_100n_0402"
			(at 369.57 105.41 0)
			(effects
				(font
					(size 1.27 1.27)
					(thickness 0.15)
				)
				(justify left bottom)
				(hide yes)
			)
		)
		(property "Footprint" "antmicro-footprints:C_0402_1005Metric"
			(at 372.11 105.41 0)
			(effects
				(font
					(size 1.27 1.27)
					(thickness 0.15)
				)
				(justify left bottom)
				(hide yes)
			)
		)
		(property "Datasheet" "https://www.murata.com/products/productdetail?partno=GRM155R61H104KE14%23"
			(at 374.65 105.41 0)
			(effects
				(font
					(size 1.27 1.27)
					(thickness 0.15)
				)
				(justify left bottom)
				(hide yes)
			)
		)
		(property "Description" ""
			(at 359.41 125.73 0)
			(effects
				(font
					(size 1.27 1.27)
				)
			)
		)
		(property "MPN" "GRM155R61H104KE14D"
			(at 377.19 105.41 0)
			(effects
				(font
					(size 1.27 1.27)
					(thickness 0.15)
				)
				(justify left bottom)
				(hide yes)
			)
		)
		(property "Manufacturer" "Murata"
			(at 379.73 105.41 0)
			(effects
				(font
					(size 1.27 1.27)
					(thickness 0.15)
				)
				(justify left bottom)
				(hide yes)
			)
		)
		(property "License" "Apache-2.0"
			(at 382.27 105.41 0)
			(effects
				(font
					(size 1.27 1.27)
					(thickness 0.15)
				)
				(justify left bottom)
				(hide yes)
			)
		)
		(property "Author" "Antmicro"
			(at 384.81 105.41 0)
			(effects
				(font
					(size 1.27 1.27)
					(thickness 0.15)
				)
				(justify left bottom)
				(hide yes)
			)
		)
		(property "Val" "100n"
			(at 360.045 125.095 90)
			(effects
				(font
					(size 1.27 1.27)
					(thickness 0.15)
				)
				(justify right)
			)
		)
		(property "Voltage" "50V"
			(at 387.35 105.41 0)
			(effects
				(font
					(size 1.27 1.27)
				)
				(justify left bottom)
				(hide yes)
			)
		)
		(property "Dielectric" "X5R"
			(at 389.89 105.41 0)
			(effects
				(font
					(size 1.27 1.27)
				)
				(justify left bottom)
				(hide yes)
			)
		)
		(pin "1"
		)
		(pin "2"
		)
		(instances
			(project "sodimm-ddr5-tester"
				(path ""
					(reference "C107")
					(unit 1)
				)
			)
		)
	)
	(symbol
		(lib_id "antmicropower:GND")
		(at 97.79 94.615 0)
		(unit 1)
		(exclude_from_sim no)
		(in_bom yes)
		(on_board yes)
		(dnp no)
		(fields_autoplaced yes)
		(property "Reference" "#PWR0109"
			(at 97.79 100.965 0)
			(effects
				(font
					(size 1.27 1.27)
				)
				(hide yes)
			)
		)
		(property "Value" "GND"
			(at 100.33 95.885 0)
			(effects
				(font
					(size 1.27 1.27)
					(thickness 0.15)
				)
				(justify left)
			)
		)
		(property "Footprint" ""
			(at 106.68 102.235 0)
			(effects
				(font
					(size 1.27 1.27)
					(thickness 0.15)
				)
				(justify left bottom)
				(hide yes)
			)
		)
		(property "Datasheet" ""
			(at 106.68 107.315 0)
			(effects
				(font
					(size 1.27 1.27)
					(thickness 0.15)
				)
				(justify left bottom)
				(hide yes)
			)
		)
		(property "Description" ""
			(at 106.68 109.855 0)
			(effects
				(font
					(size 1.27 1.27)
				)
				(justify left bottom)
				(hide yes)
			)
		)
		(property "Author" "Antmicro"
			(at 106.68 102.235 0)
			(effects
				(font
					(size 1.27 1.27)
					(thickness 0.15)
				)
				(justify left bottom)
				(hide yes)
			)
		)
		(property "License" "Apache-2.0"
			(at 106.68 104.775 0)
			(effects
				(font
					(size 1.27 1.27)
					(thickness 0.15)
				)
				(justify left bottom)
				(hide yes)
			)
		)
		(pin "1"
		)
		(instances
			(project "sodimm-ddr5-tester"
				(path ""
					(reference "#PWR0109")
					(unit 1)
				)
			)
		)
	)
	(symbol
		(lib_id "antmicropower:GND")
		(at 144.145 191.135 0)
		(unit 1)
		(exclude_from_sim no)
		(in_bom yes)
		(on_board yes)
		(dnp no)
		(fields_autoplaced yes)
		(property "Reference" "#PWR0123"
			(at 144.145 197.485 0)
			(effects
				(font
					(size 1.27 1.27)
				)
				(hide yes)
			)
		)
		(property "Value" "GND"
			(at 146.05 192.405 0)
			(effects
				(font
					(size 1.27 1.27)
					(thickness 0.15)
				)
				(justify left)
			)
		)
		(property "Footprint" ""
			(at 153.035 198.755 0)
			(effects
				(font
					(size 1.27 1.27)
					(thickness 0.15)
				)
				(justify left bottom)
				(hide yes)
			)
		)
		(property "Datasheet" ""
			(at 153.035 203.835 0)
			(effects
				(font
					(size 1.27 1.27)
					(thickness 0.15)
				)
				(justify left bottom)
				(hide yes)
			)
		)
		(property "Description" ""
			(at 153.035 206.375 0)
			(effects
				(font
					(size 1.27 1.27)
				)
				(justify left bottom)
				(hide yes)
			)
		)
		(property "Author" "Antmicro"
			(at 153.035 198.755 0)
			(effects
				(font
					(size 1.27 1.27)
					(thickness 0.15)
				)
				(justify left bottom)
				(hide yes)
			)
		)
		(property "License" "Apache-2.0"
			(at 153.035 201.295 0)
			(effects
				(font
					(size 1.27 1.27)
					(thickness 0.15)
				)
				(justify left bottom)
				(hide yes)
			)
		)
		(pin "1"
		)
		(instances
			(project "sodimm-ddr5-tester"
				(path ""
					(reference "#PWR0123")
					(unit 1)
				)
			)
		)
	)
	(symbol
		(lib_id "antmicropower:GND")
		(at 129.54 68.58 0)
		(mirror y)
		(unit 1)
		(exclude_from_sim no)
		(in_bom yes)
		(on_board yes)
		(dnp no)
		(fields_autoplaced yes)
		(property "Reference" "#PWR0119"
			(at 129.54 74.93 0)
			(effects
				(font
					(size 1.27 1.27)
				)
				(hide yes)
			)
		)
		(property "Value" "GND"
			(at 132.08 69.85 0)
			(effects
				(font
					(size 1.27 1.27)
					(thickness 0.15)
				)
				(justify right)
			)
		)
		(property "Footprint" ""
			(at 120.65 76.2 0)
			(effects
				(font
					(size 1.27 1.27)
					(thickness 0.15)
				)
				(justify left bottom)
				(hide yes)
			)
		)
		(property "Datasheet" ""
			(at 120.65 81.28 0)
			(effects
				(font
					(size 1.27 1.27)
					(thickness 0.15)
				)
				(justify left bottom)
				(hide yes)
			)
		)
		(property "Description" ""
			(at 120.65 83.82 0)
			(effects
				(font
					(size 1.27 1.27)
				)
				(justify left bottom)
				(hide yes)
			)
		)
		(property "Author" "Antmicro"
			(at 120.65 76.2 0)
			(effects
				(font
					(size 1.27 1.27)
					(thickness 0.15)
				)
				(justify left bottom)
				(hide yes)
			)
		)
		(property "License" "Apache-2.0"
			(at 120.65 78.74 0)
			(effects
				(font
					(size 1.27 1.27)
					(thickness 0.15)
				)
				(justify left bottom)
				(hide yes)
			)
		)
		(pin "1"
		)
		(instances
			(project "sodimm-ddr5-tester"
				(path ""
					(reference "#PWR0119")
					(unit 1)
				)
			)
		)
	)
	(symbol
		(lib_id "antmicroCapacitors0402:C_100n_0402")
		(at 97.79 93.345 90)
		(unit 1)
		(exclude_from_sim no)
		(in_bom yes)
		(on_board yes)
		(dnp no)
		(property "Reference" "C61"
			(at 98.425 88.9 90)
			(effects
				(font
					(size 1.27 1.27)
					(thickness 0.15)
				)
				(justify right)
			)
		)
		(property "Value" "C_100n_0402"
			(at 107.95 73.025 0)
			(effects
				(font
					(size 1.27 1.27)
					(thickness 0.15)
				)
				(justify left bottom)
				(hide yes)
			)
		)
		(property "Footprint" "antmicro-footprints:C_0402_1005Metric"
			(at 110.49 73.025 0)
			(effects
				(font
					(size 1.27 1.27)
					(thickness 0.15)
				)
				(justify left bottom)
				(hide yes)
			)
		)
		(property "Datasheet" "https://www.murata.com/products/productdetail?partno=GRM155R61H104KE14%23"
			(at 113.03 73.025 0)
			(effects
				(font
					(size 1.27 1.27)
					(thickness 0.15)
				)
				(justify left bottom)
				(hide yes)
			)
		)
		(property "Description" ""
			(at 97.79 93.345 0)
			(effects
				(font
					(size 1.27 1.27)
				)
			)
		)
		(property "MPN" "GRM155R61H104KE14D"
			(at 115.57 73.025 0)
			(effects
				(font
					(size 1.27 1.27)
					(thickness 0.15)
				)
				(justify left bottom)
				(hide yes)
			)
		)
		(property "Manufacturer" "Murata"
			(at 118.11 73.025 0)
			(effects
				(font
					(size 1.27 1.27)
					(thickness 0.15)
				)
				(justify left bottom)
				(hide yes)
			)
		)
		(property "License" "Apache-2.0"
			(at 120.65 73.025 0)
			(effects
				(font
					(size 1.27 1.27)
					(thickness 0.15)
				)
				(justify left bottom)
				(hide yes)
			)
		)
		(property "Author" "Antmicro"
			(at 123.19 73.025 0)
			(effects
				(font
					(size 1.27 1.27)
					(thickness 0.15)
				)
				(justify left bottom)
				(hide yes)
			)
		)
		(property "Val" "100n"
			(at 98.425 92.71 90)
			(effects
				(font
					(size 1.27 1.27)
					(thickness 0.15)
				)
				(justify right)
			)
		)
		(property "Voltage" "50V"
			(at 125.73 73.025 0)
			(effects
				(font
					(size 1.27 1.27)
				)
				(justify left bottom)
				(hide yes)
			)
		)
		(property "Dielectric" "X5R"
			(at 128.27 73.025 0)
			(effects
				(font
					(size 1.27 1.27)
				)
				(justify left bottom)
				(hide yes)
			)
		)
		(pin "1"
		)
		(pin "2"
		)
		(instances
			(project "sodimm-ddr5-tester"
				(path ""
					(reference "C61")
					(unit 1)
				)
			)
		)
	)
	(symbol
		(lib_id "antmicroCapacitors0402:C_100n_0402")
		(at 147.32 93.345 90)
		(unit 1)
		(exclude_from_sim no)
		(in_bom yes)
		(on_board yes)
		(dnp no)
		(property "Reference" "C86"
			(at 147.955 88.9 90)
			(effects
				(font
					(size 1.27 1.27)
					(thickness 0.15)
				)
				(justify right)
			)
		)
		(property "Value" "C_100n_0402"
			(at 157.48 73.025 0)
			(effects
				(font
					(size 1.27 1.27)
					(thickness 0.15)
				)
				(justify left bottom)
				(hide yes)
			)
		)
		(property "Footprint" "antmicro-footprints:C_0402_1005Metric"
			(at 160.02 73.025 0)
			(effects
				(font
					(size 1.27 1.27)
					(thickness 0.15)
				)
				(justify left bottom)
				(hide yes)
			)
		)
		(property "Datasheet" "https://www.murata.com/products/productdetail?partno=GRM155R61H104KE14%23"
			(at 162.56 73.025 0)
			(effects
				(font
					(size 1.27 1.27)
					(thickness 0.15)
				)
				(justify left bottom)
				(hide yes)
			)
		)
		(property "Description" ""
			(at 147.32 93.345 0)
			(effects
				(font
					(size 1.27 1.27)
				)
			)
		)
		(property "MPN" "GRM155R61H104KE14D"
			(at 165.1 73.025 0)
			(effects
				(font
					(size 1.27 1.27)
					(thickness 0.15)
				)
				(justify left bottom)
				(hide yes)
			)
		)
		(property "Manufacturer" "Murata"
			(at 167.64 73.025 0)
			(effects
				(font
					(size 1.27 1.27)
					(thickness 0.15)
				)
				(justify left bottom)
				(hide yes)
			)
		)
		(property "License" "Apache-2.0"
			(at 170.18 73.025 0)
			(effects
				(font
					(size 1.27 1.27)
					(thickness 0.15)
				)
				(justify left bottom)
				(hide yes)
			)
		)
		(property "Author" "Antmicro"
			(at 172.72 73.025 0)
			(effects
				(font
					(size 1.27 1.27)
					(thickness 0.15)
				)
				(justify left bottom)
				(hide yes)
			)
		)
		(property "Val" "100n"
			(at 147.955 92.71 90)
			(effects
				(font
					(size 1.27 1.27)
					(thickness 0.15)
				)
				(justify right)
			)
		)
		(property "Voltage" "50V"
			(at 175.26 73.025 0)
			(effects
				(font
					(size 1.27 1.27)
				)
				(justify left bottom)
				(hide yes)
			)
		)
		(property "Dielectric" "X5R"
			(at 177.8 73.025 0)
			(effects
				(font
					(size 1.27 1.27)
				)
				(justify left bottom)
				(hide yes)
			)
		)
		(pin "1"
		)
		(pin "2"
		)
		(instances
			(project "sodimm-ddr5-tester"
				(path ""
					(reference "C86")
					(unit 1)
				)
			)
		)
	)
	(symbol
		(lib_id "antmicropower:GND")
		(at 150.495 222.25 0)
		(unit 1)
		(exclude_from_sim no)
		(in_bom yes)
		(on_board yes)
		(dnp no)
		(fields_autoplaced yes)
		(property "Reference" "#PWR0144"
			(at 150.495 228.6 0)
			(effects
				(font
					(size 1.27 1.27)
				)
				(hide yes)
			)
		)
		(property "Value" "GND"
			(at 152.4 223.52 0)
			(effects
				(font
					(size 1.27 1.27)
					(thickness 0.15)
				)
				(justify left)
			)
		)
		(property "Footprint" ""
			(at 159.385 229.87 0)
			(effects
				(font
					(size 1.27 1.27)
					(thickness 0.15)
				)
				(justify left bottom)
				(hide yes)
			)
		)
		(property "Datasheet" ""
			(at 159.385 234.95 0)
			(effects
				(font
					(size 1.27 1.27)
					(thickness 0.15)
				)
				(justify left bottom)
				(hide yes)
			)
		)
		(property "Description" ""
			(at 159.385 237.49 0)
			(effects
				(font
					(size 1.27 1.27)
				)
				(justify left bottom)
				(hide yes)
			)
		)
		(property "Author" "Antmicro"
			(at 159.385 229.87 0)
			(effects
				(font
					(size 1.27 1.27)
					(thickness 0.15)
				)
				(justify left bottom)
				(hide yes)
			)
		)
		(property "License" "Apache-2.0"
			(at 159.385 232.41 0)
			(effects
				(font
					(size 1.27 1.27)
					(thickness 0.15)
				)
				(justify left bottom)
				(hide yes)
			)
		)
		(pin "1"
		)
		(instances
			(project "sodimm-ddr5-tester"
				(path ""
					(reference "#PWR0144")
					(unit 1)
				)
			)
		)
	)
	(symbol
		(lib_id "antmicroCapacitors0402:C_100n_0402")
		(at 129.54 220.345 90)
		(unit 1)
		(exclude_from_sim no)
		(in_bom yes)
		(on_board yes)
		(dnp no)
		(property "Reference" "C89"
			(at 130.175 215.9 90)
			(effects
				(font
					(size 1.27 1.27)
					(thickness 0.15)
				)
				(justify right)
			)
		)
		(property "Value" "C_100n_0402"
			(at 139.7 200.025 0)
			(effects
				(font
					(size 1.27 1.27)
					(thickness 0.15)
				)
				(justify left bottom)
				(hide yes)
			)
		)
		(property "Footprint" "antmicro-footprints:C_0402_1005Metric"
			(at 142.24 200.025 0)
			(effects
				(font
					(size 1.27 1.27)
					(thickness 0.15)
				)
				(justify left bottom)
				(hide yes)
			)
		)
		(property "Datasheet" "https://www.murata.com/products/productdetail?partno=GRM155R61H104KE14%23"
			(at 144.78 200.025 0)
			(effects
				(font
					(size 1.27 1.27)
					(thickness 0.15)
				)
				(justify left bottom)
				(hide yes)
			)
		)
		(property "Description" ""
			(at 129.54 220.345 0)
			(effects
				(font
					(size 1.27 1.27)
				)
			)
		)
		(property "MPN" "GRM155R61H104KE14D"
			(at 147.32 200.025 0)
			(effects
				(font
					(size 1.27 1.27)
					(thickness 0.15)
				)
				(justify left bottom)
				(hide yes)
			)
		)
		(property "Manufacturer" "Murata"
			(at 149.86 200.025 0)
			(effects
				(font
					(size 1.27 1.27)
					(thickness 0.15)
				)
				(justify left bottom)
				(hide yes)
			)
		)
		(property "License" "Apache-2.0"
			(at 152.4 200.025 0)
			(effects
				(font
					(size 1.27 1.27)
					(thickness 0.15)
				)
				(justify left bottom)
				(hide yes)
			)
		)
		(property "Author" "Antmicro"
			(at 154.94 200.025 0)
			(effects
				(font
					(size 1.27 1.27)
					(thickness 0.15)
				)
				(justify left bottom)
				(hide yes)
			)
		)
		(property "Val" "100n"
			(at 130.175 219.71 90)
			(effects
				(font
					(size 1.27 1.27)
					(thickness 0.15)
				)
				(justify right)
			)
		)
		(property "Voltage" "50V"
			(at 157.48 200.025 0)
			(effects
				(font
					(size 1.27 1.27)
				)
				(justify left bottom)
				(hide yes)
			)
		)
		(property "Dielectric" "X5R"
			(at 160.02 200.025 0)
			(effects
				(font
					(size 1.27 1.27)
				)
				(justify left bottom)
				(hide yes)
			)
		)
		(pin "1"
		)
		(pin "2"
		)
		(instances
			(project "sodimm-ddr5-tester"
				(path ""
					(reference "C89")
					(unit 1)
				)
			)
		)
	)
	(symbol
		(lib_id "antmicropower:GND")
		(at 137.16 191.135 0)
		(unit 1)
		(exclude_from_sim no)
		(in_bom yes)
		(on_board yes)
		(dnp no)
		(fields_autoplaced yes)
		(property "Reference" "#PWR0117"
			(at 137.16 197.485 0)
			(effects
				(font
					(size 1.27 1.27)
				)
				(hide yes)
			)
		)
		(property "Value" "GND"
			(at 139.7 192.405 0)
			(effects
				(font
					(size 1.27 1.27)
					(thickness 0.15)
				)
				(justify left)
			)
		)
		(property "Footprint" ""
			(at 146.05 198.755 0)
			(effects
				(font
					(size 1.27 1.27)
					(thickness 0.15)
				)
				(justify left bottom)
				(hide yes)
			)
		)
		(property "Datasheet" ""
			(at 146.05 203.835 0)
			(effects
				(font
					(size 1.27 1.27)
					(thickness 0.15)
				)
				(justify left bottom)
				(hide yes)
			)
		)
		(property "Description" ""
			(at 146.05 206.375 0)
			(effects
				(font
					(size 1.27 1.27)
				)
				(justify left bottom)
				(hide yes)
			)
		)
		(property "Author" "Antmicro"
			(at 146.05 198.755 0)
			(effects
				(font
					(size 1.27 1.27)
					(thickness 0.15)
				)
				(justify left bottom)
				(hide yes)
			)
		)
		(property "License" "Apache-2.0"
			(at 146.05 201.295 0)
			(effects
				(font
					(size 1.27 1.27)
					(thickness 0.15)
				)
				(justify left bottom)
				(hide yes)
			)
		)
		(pin "1"
		)
		(instances
			(project "sodimm-ddr5-tester"
				(path ""
					(reference "#PWR0117")
					(unit 1)
				)
			)
		)
	)
	(symbol
		(lib_id "antmicroCapacitors0402:C_100n_0402")
		(at 155.575 93.345 90)
		(unit 1)
		(exclude_from_sim no)
		(in_bom yes)
		(on_board yes)
		(dnp no)
		(property "Reference" "C88"
			(at 156.21 88.9 90)
			(effects
				(font
					(size 1.27 1.27)
					(thickness 0.15)
				)
				(justify right)
			)
		)
		(property "Value" "C_100n_0402"
			(at 165.735 73.025 0)
			(effects
				(font
					(size 1.27 1.27)
					(thickness 0.15)
				)
				(justify left bottom)
				(hide yes)
			)
		)
		(property "Footprint" "antmicro-footprints:C_0402_1005Metric"
			(at 168.275 73.025 0)
			(effects
				(font
					(size 1.27 1.27)
					(thickness 0.15)
				)
				(justify left bottom)
				(hide yes)
			)
		)
		(property "Datasheet" "https://www.murata.com/products/productdetail?partno=GRM155R61H104KE14%23"
			(at 170.815 73.025 0)
			(effects
				(font
					(size 1.27 1.27)
					(thickness 0.15)
				)
				(justify left bottom)
				(hide yes)
			)
		)
		(property "Description" ""
			(at 155.575 93.345 0)
			(effects
				(font
					(size 1.27 1.27)
				)
			)
		)
		(property "MPN" "GRM155R61H104KE14D"
			(at 173.355 73.025 0)
			(effects
				(font
					(size 1.27 1.27)
					(thickness 0.15)
				)
				(justify left bottom)
				(hide yes)
			)
		)
		(property "Manufacturer" "Murata"
			(at 175.895 73.025 0)
			(effects
				(font
					(size 1.27 1.27)
					(thickness 0.15)
				)
				(justify left bottom)
				(hide yes)
			)
		)
		(property "License" "Apache-2.0"
			(at 178.435 73.025 0)
			(effects
				(font
					(size 1.27 1.27)
					(thickness 0.15)
				)
				(justify left bottom)
				(hide yes)
			)
		)
		(property "Author" "Antmicro"
			(at 180.975 73.025 0)
			(effects
				(font
					(size 1.27 1.27)
					(thickness 0.15)
				)
				(justify left bottom)
				(hide yes)
			)
		)
		(property "Val" "100n"
			(at 156.21 92.71 90)
			(effects
				(font
					(size 1.27 1.27)
					(thickness 0.15)
				)
				(justify right)
			)
		)
		(property "Voltage" "50V"
			(at 183.515 73.025 0)
			(effects
				(font
					(size 1.27 1.27)
				)
				(justify left bottom)
				(hide yes)
			)
		)
		(property "Dielectric" "X5R"
			(at 186.055 73.025 0)
			(effects
				(font
					(size 1.27 1.27)
				)
				(justify left bottom)
				(hide yes)
			)
		)
		(pin "1"
		)
		(pin "2"
		)
		(instances
			(project "sodimm-ddr5-tester"
				(path ""
					(reference "C88")
					(unit 1)
				)
			)
		)
	)
	(symbol
		(lib_id "antmicropower:GND")
		(at 59.69 220.98 0)
		(unit 1)
		(exclude_from_sim no)
		(in_bom yes)
		(on_board yes)
		(dnp no)
		(fields_autoplaced yes)
		(property "Reference" "#PWR083"
			(at 59.69 227.33 0)
			(effects
				(font
					(size 1.27 1.27)
				)
				(hide yes)
			)
		)
		(property "Value" "GND"
			(at 62.23 222.25 0)
			(effects
				(font
					(size 1.27 1.27)
					(thickness 0.15)
				)
				(justify left)
			)
		)
		(property "Footprint" ""
			(at 68.58 228.6 0)
			(effects
				(font
					(size 1.27 1.27)
					(thickness 0.15)
				)
				(justify left bottom)
				(hide yes)
			)
		)
		(property "Datasheet" ""
			(at 68.58 233.68 0)
			(effects
				(font
					(size 1.27 1.27)
					(thickness 0.15)
				)
				(justify left bottom)
				(hide yes)
			)
		)
		(property "Description" ""
			(at 68.58 236.22 0)
			(effects
				(font
					(size 1.27 1.27)
				)
				(justify left bottom)
				(hide yes)
			)
		)
		(property "Author" "Antmicro"
			(at 68.58 228.6 0)
			(effects
				(font
					(size 1.27 1.27)
					(thickness 0.15)
				)
				(justify left bottom)
				(hide yes)
			)
		)
		(property "License" "Apache-2.0"
			(at 68.58 231.14 0)
			(effects
				(font
					(size 1.27 1.27)
					(thickness 0.15)
				)
				(justify left bottom)
				(hide yes)
			)
		)
		(pin "1"
		)
		(instances
			(project "sodimm-ddr5-tester"
				(path ""
					(reference "#PWR083")
					(unit 1)
				)
			)
		)
	)
	(symbol
		(lib_id "antmicroCapacitors0402:C_4u7_0402")
		(at 64.135 117.475 270)
		(unit 1)
		(exclude_from_sim no)
		(in_bom yes)
		(on_board yes)
		(dnp no)
		(property "Reference" "C34"
			(at 64.77 118.11 90)
			(effects
				(font
					(size 1.27 1.27)
				)
				(justify left)
			)
		)
		(property "Value" "C_4u7_0402"
			(at 53.975 137.795 0)
			(effects
				(font
					(size 1.27 1.27)
					(thickness 0.15)
				)
				(justify left bottom)
				(hide yes)
			)
		)
		(property "Footprint" "antmicro-footprints:C_0402_1005Metric"
			(at 51.435 137.795 0)
			(effects
				(font
					(size 1.27 1.27)
					(thickness 0.15)
				)
				(justify left bottom)
				(hide yes)
			)
		)
		(property "Datasheet" "https://www.murata.com/products/productdetail?partno=GRM155R61A475MEAA%23"
			(at 48.895 137.795 0)
			(effects
				(font
					(size 1.27 1.27)
					(thickness 0.15)
				)
				(justify left bottom)
				(hide yes)
			)
		)
		(property "Description" ""
			(at 64.135 117.475 0)
			(effects
				(font
					(size 1.27 1.27)
				)
			)
		)
		(property "Manufacturer" "Murata"
			(at 43.815 137.795 0)
			(effects
				(font
					(size 1.27 1.27)
					(thickness 0.15)
				)
				(justify left bottom)
				(hide yes)
			)
		)
		(property "MPN" "GRM155R61A475MEAAD"
			(at 46.355 137.795 0)
			(effects
				(font
					(size 1.27 1.27)
					(thickness 0.15)
				)
				(justify left bottom)
				(hide yes)
			)
		)
		(property "Val" "4u7"
			(at 64.77 121.92 90)
			(effects
				(font
					(size 1.27 1.27)
					(thickness 0.15)
				)
				(justify left)
			)
		)
		(property "License" "Apache-2.0"
			(at 41.275 137.795 0)
			(effects
				(font
					(size 1.27 1.27)
					(thickness 0.15)
				)
				(justify left bottom)
				(hide yes)
			)
		)
		(property "Author" "Antmicro"
			(at 38.735 137.795 0)
			(effects
				(font
					(size 1.27 1.27)
					(thickness 0.15)
				)
				(justify left bottom)
				(hide yes)
			)
		)
		(property "Voltage" ""
			(at 36.195 137.795 0)
			(effects
				(font
					(size 1.27 1.27)
				)
				(justify left bottom)
				(hide yes)
			)
		)
		(property "Dielectric" ""
			(at 33.655 137.795 0)
			(effects
				(font
					(size 1.27 1.27)
				)
				(justify left bottom)
				(hide yes)
			)
		)
		(pin "1"
		)
		(pin "2"
		)
		(instances
			(project "sodimm-ddr5-tester"
				(path ""
					(reference "C34")
					(unit 1)
				)
			)
		)
	)
	(symbol
		(lib_id "antmicroCapacitors0402:C_100n_0402")
		(at 87.63 219.71 90)
		(unit 1)
		(exclude_from_sim no)
		(in_bom yes)
		(on_board yes)
		(dnp no)
		(property "Reference" "C59"
			(at 88.265 215.265 90)
			(effects
				(font
					(size 1.27 1.27)
					(thickness 0.15)
				)
				(justify right)
			)
		)
		(property "Value" "C_100n_0402"
			(at 97.79 199.39 0)
			(effects
				(font
					(size 1.27 1.27)
					(thickness 0.15)
				)
				(justify left bottom)
				(hide yes)
			)
		)
		(property "Footprint" "antmicro-footprints:C_0402_1005Metric"
			(at 100.33 199.39 0)
			(effects
				(font
					(size 1.27 1.27)
					(thickness 0.15)
				)
				(justify left bottom)
				(hide yes)
			)
		)
		(property "Datasheet" "https://www.murata.com/products/productdetail?partno=GRM155R61H104KE14%23"
			(at 102.87 199.39 0)
			(effects
				(font
					(size 1.27 1.27)
					(thickness 0.15)
				)
				(justify left bottom)
				(hide yes)
			)
		)
		(property "Description" ""
			(at 87.63 219.71 0)
			(effects
				(font
					(size 1.27 1.27)
				)
			)
		)
		(property "MPN" "GRM155R61H104KE14D"
			(at 105.41 199.39 0)
			(effects
				(font
					(size 1.27 1.27)
					(thickness 0.15)
				)
				(justify left bottom)
				(hide yes)
			)
		)
		(property "Manufacturer" "Murata"
			(at 107.95 199.39 0)
			(effects
				(font
					(size 1.27 1.27)
					(thickness 0.15)
				)
				(justify left bottom)
				(hide yes)
			)
		)
		(property "License" "Apache-2.0"
			(at 110.49 199.39 0)
			(effects
				(font
					(size 1.27 1.27)
					(thickness 0.15)
				)
				(justify left bottom)
				(hide yes)
			)
		)
		(property "Author" "Antmicro"
			(at 113.03 199.39 0)
			(effects
				(font
					(size 1.27 1.27)
					(thickness 0.15)
				)
				(justify left bottom)
				(hide yes)
			)
		)
		(property "Val" "100n"
			(at 88.265 219.075 90)
			(effects
				(font
					(size 1.27 1.27)
					(thickness 0.15)
				)
				(justify right)
			)
		)
		(property "Voltage" "50V"
			(at 115.57 199.39 0)
			(effects
				(font
					(size 1.27 1.27)
				)
				(justify left bottom)
				(hide yes)
			)
		)
		(property "Dielectric" "X5R"
			(at 118.11 199.39 0)
			(effects
				(font
					(size 1.27 1.27)
				)
				(justify left bottom)
				(hide yes)
			)
		)
		(pin "1"
		)
		(pin "2"
		)
		(instances
			(project "sodimm-ddr5-tester"
				(path ""
					(reference "C59")
					(unit 1)
				)
			)
		)
	)
	(symbol
		(lib_id "antmicroCapacitors0402:C_100n_0402")
		(at 144.145 189.23 90)
		(unit 1)
		(exclude_from_sim no)
		(in_bom yes)
		(on_board yes)
		(dnp no)
		(property "Reference" "C74"
			(at 144.78 184.785 90)
			(effects
				(font
					(size 1.27 1.27)
					(thickness 0.15)
				)
				(justify right)
			)
		)
		(property "Value" "C_100n_0402"
			(at 154.305 168.91 0)
			(effects
				(font
					(size 1.27 1.27)
					(thickness 0.15)
				)
				(justify left bottom)
				(hide yes)
			)
		)
		(property "Footprint" "antmicro-footprints:C_0402_1005Metric"
			(at 156.845 168.91 0)
			(effects
				(font
					(size 1.27 1.27)
					(thickness 0.15)
				)
				(justify left bottom)
				(hide yes)
			)
		)
		(property "Datasheet" "https://www.murata.com/products/productdetail?partno=GRM155R61H104KE14%23"
			(at 159.385 168.91 0)
			(effects
				(font
					(size 1.27 1.27)
					(thickness 0.15)
				)
				(justify left bottom)
				(hide yes)
			)
		)
		(property "Description" ""
			(at 144.145 189.23 0)
			(effects
				(font
					(size 1.27 1.27)
				)
			)
		)
		(property "MPN" "GRM155R61H104KE14D"
			(at 161.925 168.91 0)
			(effects
				(font
					(size 1.27 1.27)
					(thickness 0.15)
				)
				(justify left bottom)
				(hide yes)
			)
		)
		(property "Manufacturer" "Murata"
			(at 164.465 168.91 0)
			(effects
				(font
					(size 1.27 1.27)
					(thickness 0.15)
				)
				(justify left bottom)
				(hide yes)
			)
		)
		(property "License" "Apache-2.0"
			(at 167.005 168.91 0)
			(effects
				(font
					(size 1.27 1.27)
					(thickness 0.15)
				)
				(justify left bottom)
				(hide yes)
			)
		)
		(property "Author" "Antmicro"
			(at 169.545 168.91 0)
			(effects
				(font
					(size 1.27 1.27)
					(thickness 0.15)
				)
				(justify left bottom)
				(hide yes)
			)
		)
		(property "Val" "100n"
			(at 144.78 188.595 90)
			(effects
				(font
					(size 1.27 1.27)
					(thickness 0.15)
				)
				(justify right)
			)
		)
		(property "Voltage" "50V"
			(at 172.085 168.91 0)
			(effects
				(font
					(size 1.27 1.27)
				)
				(justify left bottom)
				(hide yes)
			)
		)
		(property "Dielectric" "X5R"
			(at 174.625 168.91 0)
			(effects
				(font
					(size 1.27 1.27)
				)
				(justify left bottom)
				(hide yes)
			)
		)
		(pin "1"
		)
		(pin "2"
		)
		(instances
			(project "sodimm-ddr5-tester"
				(path ""
					(reference "C74")
					(unit 1)
				)
			)
		)
	)
	(symbol
		(lib_id "antmicroCapacitors0402:C_100n_0402")
		(at 81.28 93.345 90)
		(unit 1)
		(exclude_from_sim no)
		(in_bom yes)
		(on_board yes)
		(dnp no)
		(property "Reference" "C48"
			(at 81.915 88.9 90)
			(effects
				(font
					(size 1.27 1.27)
					(thickness 0.15)
				)
				(justify right)
			)
		)
		(property "Value" "C_100n_0402"
			(at 91.44 73.025 0)
			(effects
				(font
					(size 1.27 1.27)
					(thickness 0.15)
				)
				(justify left bottom)
				(hide yes)
			)
		)
		(property "Footprint" "antmicro-footprints:C_0402_1005Metric"
			(at 93.98 73.025 0)
			(effects
				(font
					(size 1.27 1.27)
					(thickness 0.15)
				)
				(justify left bottom)
				(hide yes)
			)
		)
		(property "Datasheet" "https://www.murata.com/products/productdetail?partno=GRM155R61H104KE14%23"
			(at 96.52 73.025 0)
			(effects
				(font
					(size 1.27 1.27)
					(thickness 0.15)
				)
				(justify left bottom)
				(hide yes)
			)
		)
		(property "Description" ""
			(at 81.28 93.345 0)
			(effects
				(font
					(size 1.27 1.27)
				)
			)
		)
		(property "MPN" "GRM155R61H104KE14D"
			(at 99.06 73.025 0)
			(effects
				(font
					(size 1.27 1.27)
					(thickness 0.15)
				)
				(justify left bottom)
				(hide yes)
			)
		)
		(property "Manufacturer" "Murata"
			(at 101.6 73.025 0)
			(effects
				(font
					(size 1.27 1.27)
					(thickness 0.15)
				)
				(justify left bottom)
				(hide yes)
			)
		)
		(property "License" "Apache-2.0"
			(at 104.14 73.025 0)
			(effects
				(font
					(size 1.27 1.27)
					(thickness 0.15)
				)
				(justify left bottom)
				(hide yes)
			)
		)
		(property "Author" "Antmicro"
			(at 106.68 73.025 0)
			(effects
				(font
					(size 1.27 1.27)
					(thickness 0.15)
				)
				(justify left bottom)
				(hide yes)
			)
		)
		(property "Val" "100n"
			(at 81.915 92.71 90)
			(effects
				(font
					(size 1.27 1.27)
					(thickness 0.15)
				)
				(justify right)
			)
		)
		(property "Voltage" "50V"
			(at 109.22 73.025 0)
			(effects
				(font
					(size 1.27 1.27)
				)
				(justify left bottom)
				(hide yes)
			)
		)
		(property "Dielectric" "X5R"
			(at 111.76 73.025 0)
			(effects
				(font
					(size 1.27 1.27)
				)
				(justify left bottom)
				(hide yes)
			)
		)
		(pin "1"
		)
		(pin "2"
		)
		(instances
			(project "sodimm-ddr5-tester"
				(path ""
					(reference "C48")
					(unit 1)
				)
			)
		)
	)
	(symbol
		(lib_id "antmicroCapacitors0402:C_100n_0402")
		(at 130.175 160.655 90)
		(unit 1)
		(exclude_from_sim no)
		(in_bom yes)
		(on_board yes)
		(dnp no)
		(property "Reference" "C24"
			(at 130.81 156.21 90)
			(effects
				(font
					(size 1.27 1.27)
					(thickness 0.15)
				)
				(justify right)
			)
		)
		(property "Value" "C_100n_0402"
			(at 140.335 140.335 0)
			(effects
				(font
					(size 1.27 1.27)
					(thickness 0.15)
				)
				(justify left bottom)
				(hide yes)
			)
		)
		(property "Footprint" "antmicro-footprints:C_0402_1005Metric"
			(at 142.875 140.335 0)
			(effects
				(font
					(size 1.27 1.27)
					(thickness 0.15)
				)
				(justify left bottom)
				(hide yes)
			)
		)
		(property "Datasheet" "https://www.murata.com/products/productdetail?partno=GRM155R61H104KE14%23"
			(at 145.415 140.335 0)
			(effects
				(font
					(size 1.27 1.27)
					(thickness 0.15)
				)
				(justify left bottom)
				(hide yes)
			)
		)
		(property "Description" ""
			(at 130.175 160.655 0)
			(effects
				(font
					(size 1.27 1.27)
				)
			)
		)
		(property "MPN" "GRM155R61H104KE14D"
			(at 147.955 140.335 0)
			(effects
				(font
					(size 1.27 1.27)
					(thickness 0.15)
				)
				(justify left bottom)
				(hide yes)
			)
		)
		(property "Manufacturer" "Murata"
			(at 150.495 140.335 0)
			(effects
				(font
					(size 1.27 1.27)
					(thickness 0.15)
				)
				(justify left bottom)
				(hide yes)
			)
		)
		(property "License" "Apache-2.0"
			(at 153.035 140.335 0)
			(effects
				(font
					(size 1.27 1.27)
					(thickness 0.15)
				)
				(justify left bottom)
				(hide yes)
			)
		)
		(property "Author" "Antmicro"
			(at 155.575 140.335 0)
			(effects
				(font
					(size 1.27 1.27)
					(thickness 0.15)
				)
				(justify left bottom)
				(hide yes)
			)
		)
		(property "Val" "100n"
			(at 130.81 160.02 90)
			(effects
				(font
					(size 1.27 1.27)
					(thickness 0.15)
				)
				(justify right)
			)
		)
		(property "Voltage" "50V"
			(at 158.115 140.335 0)
			(effects
				(font
					(size 1.27 1.27)
				)
				(justify left bottom)
				(hide yes)
			)
		)
		(property "Dielectric" "X5R"
			(at 160.655 140.335 0)
			(effects
				(font
					(size 1.27 1.27)
				)
				(justify left bottom)
				(hide yes)
			)
		)
		(pin "1"
		)
		(pin "2"
		)
		(instances
			(project "sodimm-ddr5-tester"
				(path ""
					(reference "C24")
					(unit 1)
				)
			)
		)
	)
	(symbol
		(lib_id "antmicropower:GND")
		(at 64.135 124.46 0)
		(mirror y)
		(unit 1)
		(exclude_from_sim no)
		(in_bom yes)
		(on_board yes)
		(dnp no)
		(fields_autoplaced yes)
		(property "Reference" "#PWR081"
			(at 64.135 130.81 0)
			(effects
				(font
					(size 1.27 1.27)
				)
				(hide yes)
			)
		)
		(property "Value" "GND"
			(at 66.04 125.73 0)
			(effects
				(font
					(size 1.27 1.27)
					(thickness 0.15)
				)
				(justify right)
			)
		)
		(property "Footprint" ""
			(at 55.245 132.08 0)
			(effects
				(font
					(size 1.27 1.27)
					(thickness 0.15)
				)
				(justify left bottom)
				(hide yes)
			)
		)
		(property "Datasheet" ""
			(at 55.245 137.16 0)
			(effects
				(font
					(size 1.27 1.27)
					(thickness 0.15)
				)
				(justify left bottom)
				(hide yes)
			)
		)
		(property "Description" ""
			(at 55.245 139.7 0)
			(effects
				(font
					(size 1.27 1.27)
				)
				(justify left bottom)
				(hide yes)
			)
		)
		(property "Author" "Antmicro"
			(at 55.245 132.08 0)
			(effects
				(font
					(size 1.27 1.27)
					(thickness 0.15)
				)
				(justify left bottom)
				(hide yes)
			)
		)
		(property "License" "Apache-2.0"
			(at 55.245 134.62 0)
			(effects
				(font
					(size 1.27 1.27)
					(thickness 0.15)
				)
				(justify left bottom)
				(hide yes)
			)
		)
		(pin "1"
		)
		(instances
			(project "sodimm-ddr5-tester"
				(path ""
					(reference "#PWR081")
					(unit 1)
				)
			)
		)
	)
	(symbol
		(lib_id "antmicropower:GND")
		(at 45.72 190.5 0)
		(unit 1)
		(exclude_from_sim no)
		(in_bom yes)
		(on_board yes)
		(dnp no)
		(fields_autoplaced yes)
		(property "Reference" "#PWR069"
			(at 45.72 196.85 0)
			(effects
				(font
					(size 1.27 1.27)
				)
				(hide yes)
			)
		)
		(property "Value" "GND"
			(at 48.26 191.77 0)
			(effects
				(font
					(size 1.27 1.27)
					(thickness 0.15)
				)
				(justify left)
			)
		)
		(property "Footprint" ""
			(at 54.61 198.12 0)
			(effects
				(font
					(size 1.27 1.27)
					(thickness 0.15)
				)
				(justify left bottom)
				(hide yes)
			)
		)
		(property "Datasheet" ""
			(at 54.61 203.2 0)
			(effects
				(font
					(size 1.27 1.27)
					(thickness 0.15)
				)
				(justify left bottom)
				(hide yes)
			)
		)
		(property "Description" ""
			(at 54.61 205.74 0)
			(effects
				(font
					(size 1.27 1.27)
				)
				(justify left bottom)
				(hide yes)
			)
		)
		(property "Author" "Antmicro"
			(at 54.61 198.12 0)
			(effects
				(font
					(size 1.27 1.27)
					(thickness 0.15)
				)
				(justify left bottom)
				(hide yes)
			)
		)
		(property "License" "Apache-2.0"
			(at 54.61 200.66 0)
			(effects
				(font
					(size 1.27 1.27)
					(thickness 0.15)
				)
				(justify left bottom)
				(hide yes)
			)
		)
		(pin "1"
		)
		(instances
			(project "sodimm-ddr5-tester"
				(path ""
					(reference "#PWR069")
					(unit 1)
				)
			)
		)
	)
	(symbol
		(lib_id "antmicropower:+1V2_MGTAVTT")
		(at 330.2 116.84 0)
		(unit 1)
		(exclude_from_sim no)
		(in_bom yes)
		(on_board yes)
		(dnp no)
		(fields_autoplaced yes)
		(property "Reference" "#PWR0160"
			(at 330.2 120.65 0)
			(effects
				(font
					(size 1.27 1.27)
				)
				(hide yes)
			)
		)
		(property "Value" "+1V2_MGTAVTT"
			(at 330.2 113.03 0)
			(effects
				(font
					(size 1.27 1.27)
				)
			)
		)
		(property "Footprint" ""
			(at 330.2 116.84 0)
			(effects
				(font
					(size 1.27 1.27)
				)
				(hide yes)
			)
		)
		(property "Datasheet" ""
			(at 330.2 116.84 0)
			(effects
				(font
					(size 1.27 1.27)
				)
				(hide yes)
			)
		)
		(property "Description" ""
			(at 330.2 116.84 0)
			(effects
				(font
					(size 1.27 1.27)
				)
			)
		)
		(pin "1"
		)
		(instances
			(project "sodimm-ddr5-tester"
				(path ""
					(reference "#PWR0160")
					(unit 1)
				)
			)
		)
	)
	(symbol
		(lib_id "antmicropower:GND")
		(at 130.81 94.615 0)
		(unit 1)
		(exclude_from_sim no)
		(in_bom yes)
		(on_board yes)
		(dnp no)
		(fields_autoplaced yes)
		(property "Reference" "#PWR0128"
			(at 130.81 100.965 0)
			(effects
				(font
					(size 1.27 1.27)
				)
				(hide yes)
			)
		)
		(property "Value" "GND"
			(at 133.35 95.885 0)
			(effects
				(font
					(size 1.27 1.27)
					(thickness 0.15)
				)
				(justify left)
			)
		)
		(property "Footprint" ""
			(at 139.7 102.235 0)
			(effects
				(font
					(size 1.27 1.27)
					(thickness 0.15)
				)
				(justify left bottom)
				(hide yes)
			)
		)
		(property "Datasheet" ""
			(at 139.7 107.315 0)
			(effects
				(font
					(size 1.27 1.27)
					(thickness 0.15)
				)
				(justify left bottom)
				(hide yes)
			)
		)
		(property "Description" ""
			(at 139.7 109.855 0)
			(effects
				(font
					(size 1.27 1.27)
				)
				(justify left bottom)
				(hide yes)
			)
		)
		(property "Author" "Antmicro"
			(at 139.7 102.235 0)
			(effects
				(font
					(size 1.27 1.27)
					(thickness 0.15)
				)
				(justify left bottom)
				(hide yes)
			)
		)
		(property "License" "Apache-2.0"
			(at 139.7 104.775 0)
			(effects
				(font
					(size 1.27 1.27)
					(thickness 0.15)
				)
				(justify left bottom)
				(hide yes)
			)
		)
		(pin "1"
		)
		(instances
			(project "sodimm-ddr5-tester"
				(path ""
					(reference "#PWR0128")
					(unit 1)
				)
			)
		)
	)
	(symbol
		(lib_id "antmicroCapacitors0402:C_100n_0402")
		(at 151.13 189.23 90)
		(unit 1)
		(exclude_from_sim no)
		(in_bom yes)
		(on_board yes)
		(dnp no)
		(property "Reference" "C78"
			(at 151.765 184.785 90)
			(effects
				(font
					(size 1.27 1.27)
					(thickness 0.15)
				)
				(justify right)
			)
		)
		(property "Value" "C_100n_0402"
			(at 161.29 168.91 0)
			(effects
				(font
					(size 1.27 1.27)
					(thickness 0.15)
				)
				(justify left bottom)
				(hide yes)
			)
		)
		(property "Footprint" "antmicro-footprints:C_0402_1005Metric"
			(at 163.83 168.91 0)
			(effects
				(font
					(size 1.27 1.27)
					(thickness 0.15)
				)
				(justify left bottom)
				(hide yes)
			)
		)
		(property "Datasheet" "https://www.murata.com/products/productdetail?partno=GRM155R61H104KE14%23"
			(at 166.37 168.91 0)
			(effects
				(font
					(size 1.27 1.27)
					(thickness 0.15)
				)
				(justify left bottom)
				(hide yes)
			)
		)
		(property "Description" ""
			(at 151.13 189.23 0)
			(effects
				(font
					(size 1.27 1.27)
				)
			)
		)
		(property "MPN" "GRM155R61H104KE14D"
			(at 168.91 168.91 0)
			(effects
				(font
					(size 1.27 1.27)
					(thickness 0.15)
				)
				(justify left bottom)
				(hide yes)
			)
		)
		(property "Manufacturer" "Murata"
			(at 171.45 168.91 0)
			(effects
				(font
					(size 1.27 1.27)
					(thickness 0.15)
				)
				(justify left bottom)
				(hide yes)
			)
		)
		(property "License" "Apache-2.0"
			(at 173.99 168.91 0)
			(effects
				(font
					(size 1.27 1.27)
					(thickness 0.15)
				)
				(justify left bottom)
				(hide yes)
			)
		)
		(property "Author" "Antmicro"
			(at 176.53 168.91 0)
			(effects
				(font
					(size 1.27 1.27)
					(thickness 0.15)
				)
				(justify left bottom)
				(hide yes)
			)
		)
		(property "Val" "100n"
			(at 151.765 188.595 90)
			(effects
				(font
					(size 1.27 1.27)
					(thickness 0.15)
				)
				(justify right)
			)
		)
		(property "Voltage" "50V"
			(at 179.07 168.91 0)
			(effects
				(font
					(size 1.27 1.27)
				)
				(justify left bottom)
				(hide yes)
			)
		)
		(property "Dielectric" "X5R"
			(at 181.61 168.91 0)
			(effects
				(font
					(size 1.27 1.27)
				)
				(justify left bottom)
				(hide yes)
			)
		)
		(pin "1"
		)
		(pin "2"
		)
		(instances
			(project "sodimm-ddr5-tester"
				(path ""
					(reference "C78")
					(unit 1)
				)
			)
		)
	)
	(symbol
		(lib_id "antmicroCapacitors0402:C_100n_0402")
		(at 45.72 189.23 90)
		(unit 1)
		(exclude_from_sim no)
		(in_bom yes)
		(on_board yes)
		(dnp no)
		(property "Reference" "C22"
			(at 52.705 184.785 90)
			(effects
				(font
					(size 1.27 1.27)
					(thickness 0.15)
				)
				(justify left)
			)
		)
		(property "Value" "C_100n_0402"
			(at 55.88 168.91 0)
			(effects
				(font
					(size 1.27 1.27)
					(thickness 0.15)
				)
				(justify left bottom)
				(hide yes)
			)
		)
		(property "Footprint" "antmicro-footprints:C_0402_1005Metric"
			(at 58.42 168.91 0)
			(effects
				(font
					(size 1.27 1.27)
					(thickness 0.15)
				)
				(justify left bottom)
				(hide yes)
			)
		)
		(property "Datasheet" "https://www.murata.com/products/productdetail?partno=GRM155R61H104KE14%23"
			(at 60.96 168.91 0)
			(effects
				(font
					(size 1.27 1.27)
					(thickness 0.15)
				)
				(justify left bottom)
				(hide yes)
			)
		)
		(property "Description" ""
			(at 45.72 189.23 0)
			(effects
				(font
					(size 1.27 1.27)
				)
			)
		)
		(property "MPN" "GRM155R61H104KE14D"
			(at 63.5 168.91 0)
			(effects
				(font
					(size 1.27 1.27)
					(thickness 0.15)
				)
				(justify left bottom)
				(hide yes)
			)
		)
		(property "Manufacturer" "Murata"
			(at 66.04 168.91 0)
			(effects
				(font
					(size 1.27 1.27)
					(thickness 0.15)
				)
				(justify left bottom)
				(hide yes)
			)
		)
		(property "License" "Apache-2.0"
			(at 68.58 168.91 0)
			(effects
				(font
					(size 1.27 1.27)
					(thickness 0.15)
				)
				(justify left bottom)
				(hide yes)
			)
		)
		(property "Author" "Antmicro"
			(at 71.12 168.91 0)
			(effects
				(font
					(size 1.27 1.27)
					(thickness 0.15)
				)
				(justify left bottom)
				(hide yes)
			)
		)
		(property "Val" "100n"
			(at 51.435 188.595 90)
			(effects
				(font
					(size 1.27 1.27)
					(thickness 0.15)
				)
				(justify left)
			)
		)
		(property "Voltage" "50V"
			(at 73.66 168.91 0)
			(effects
				(font
					(size 1.27 1.27)
				)
				(justify left bottom)
				(hide yes)
			)
		)
		(property "Dielectric" "X5R"
			(at 76.2 168.91 0)
			(effects
				(font
					(size 1.27 1.27)
				)
				(justify left bottom)
				(hide yes)
			)
		)
		(pin "1"
		)
		(pin "2"
		)
		(instances
			(project "sodimm-ddr5-tester"
				(path ""
					(reference "C22")
					(unit 1)
				)
			)
		)
	)
	(symbol
		(lib_id "antmicropower:GND")
		(at 38.1 248.92 0)
		(unit 1)
		(exclude_from_sim no)
		(in_bom yes)
		(on_board yes)
		(dnp no)
		(fields_autoplaced yes)
		(property "Reference" "#PWR060"
			(at 38.1 255.27 0)
			(effects
				(font
					(size 1.27 1.27)
				)
				(hide yes)
			)
		)
		(property "Value" "GND"
			(at 40.64 250.19 0)
			(effects
				(font
					(size 1.27 1.27)
					(thickness 0.15)
				)
				(justify left)
			)
		)
		(property "Footprint" ""
			(at 46.99 256.54 0)
			(effects
				(font
					(size 1.27 1.27)
					(thickness 0.15)
				)
				(justify left bottom)
				(hide yes)
			)
		)
		(property "Datasheet" ""
			(at 46.99 261.62 0)
			(effects
				(font
					(size 1.27 1.27)
					(thickness 0.15)
				)
				(justify left bottom)
				(hide yes)
			)
		)
		(property "Description" ""
			(at 46.99 264.16 0)
			(effects
				(font
					(size 1.27 1.27)
				)
				(justify left bottom)
				(hide yes)
			)
		)
		(property "Author" "Antmicro"
			(at 46.99 256.54 0)
			(effects
				(font
					(size 1.27 1.27)
					(thickness 0.15)
				)
				(justify left bottom)
				(hide yes)
			)
		)
		(property "License" "Apache-2.0"
			(at 46.99 259.08 0)
			(effects
				(font
					(size 1.27 1.27)
					(thickness 0.15)
				)
				(justify left bottom)
				(hide yes)
			)
		)
		(pin "1"
		)
		(instances
			(project "sodimm-ddr5-tester"
				(path ""
					(reference "#PWR060")
					(unit 1)
				)
			)
		)
	)
	(symbol
		(lib_id "antmicropower:GND")
		(at 73.66 124.46 0)
		(mirror y)
		(unit 1)
		(exclude_from_sim no)
		(in_bom yes)
		(on_board yes)
		(dnp no)
		(fields_autoplaced yes)
		(property "Reference" "#PWR090"
			(at 73.66 130.81 0)
			(effects
				(font
					(size 1.27 1.27)
				)
				(hide yes)
			)
		)
		(property "Value" "GND"
			(at 76.2 125.73 0)
			(effects
				(font
					(size 1.27 1.27)
					(thickness 0.15)
				)
				(justify right)
			)
		)
		(property "Footprint" ""
			(at 64.77 132.08 0)
			(effects
				(font
					(size 1.27 1.27)
					(thickness 0.15)
				)
				(justify left bottom)
				(hide yes)
			)
		)
		(property "Datasheet" ""
			(at 64.77 137.16 0)
			(effects
				(font
					(size 1.27 1.27)
					(thickness 0.15)
				)
				(justify left bottom)
				(hide yes)
			)
		)
		(property "Description" ""
			(at 64.77 139.7 0)
			(effects
				(font
					(size 1.27 1.27)
				)
				(justify left bottom)
				(hide yes)
			)
		)
		(property "Author" "Antmicro"
			(at 64.77 132.08 0)
			(effects
				(font
					(size 1.27 1.27)
					(thickness 0.15)
				)
				(justify left bottom)
				(hide yes)
			)
		)
		(property "License" "Apache-2.0"
			(at 64.77 134.62 0)
			(effects
				(font
					(size 1.27 1.27)
					(thickness 0.15)
				)
				(justify left bottom)
				(hide yes)
			)
		)
		(pin "1"
		)
		(instances
			(project "sodimm-ddr5-tester"
				(path ""
					(reference "#PWR090")
					(unit 1)
				)
			)
		)
	)
	(symbol
		(lib_id "antmicropower:GND")
		(at 123.19 162.56 0)
		(unit 1)
		(exclude_from_sim no)
		(in_bom yes)
		(on_board yes)
		(dnp no)
		(fields_autoplaced yes)
		(property "Reference" "#PWR067"
			(at 123.19 168.91 0)
			(effects
				(font
					(size 1.27 1.27)
				)
				(hide yes)
			)
		)
		(property "Value" "GND"
			(at 125.73 163.83 0)
			(effects
				(font
					(size 1.27 1.27)
					(thickness 0.15)
				)
				(justify left)
			)
		)
		(property "Footprint" ""
			(at 132.08 170.18 0)
			(effects
				(font
					(size 1.27 1.27)
					(thickness 0.15)
				)
				(justify left bottom)
				(hide yes)
			)
		)
		(property "Datasheet" ""
			(at 132.08 175.26 0)
			(effects
				(font
					(size 1.27 1.27)
					(thickness 0.15)
				)
				(justify left bottom)
				(hide yes)
			)
		)
		(property "Description" ""
			(at 132.08 177.8 0)
			(effects
				(font
					(size 1.27 1.27)
				)
				(justify left bottom)
				(hide yes)
			)
		)
		(property "Author" "Antmicro"
			(at 132.08 170.18 0)
			(effects
				(font
					(size 1.27 1.27)
					(thickness 0.15)
				)
				(justify left bottom)
				(hide yes)
			)
		)
		(property "License" "Apache-2.0"
			(at 132.08 172.72 0)
			(effects
				(font
					(size 1.27 1.27)
					(thickness 0.15)
				)
				(justify left bottom)
				(hide yes)
			)
		)
		(pin "1"
		)
		(instances
			(project "sodimm-ddr5-tester"
				(path ""
					(reference "#PWR067")
					(unit 1)
				)
			)
		)
	)
	(symbol
		(lib_id "antmicroCapacitors0402:C_100n_0402")
		(at 73.66 219.71 90)
		(unit 1)
		(exclude_from_sim no)
		(in_bom yes)
		(on_board yes)
		(dnp no)
		(property "Reference" "C47"
			(at 74.295 215.265 90)
			(effects
				(font
					(size 1.27 1.27)
					(thickness 0.15)
				)
				(justify right)
			)
		)
		(property "Value" "C_100n_0402"
			(at 83.82 199.39 0)
			(effects
				(font
					(size 1.27 1.27)
					(thickness 0.15)
				)
				(justify left bottom)
				(hide yes)
			)
		)
		(property "Footprint" "antmicro-footprints:C_0402_1005Metric"
			(at 86.36 199.39 0)
			(effects
				(font
					(size 1.27 1.27)
					(thickness 0.15)
				)
				(justify left bottom)
				(hide yes)
			)
		)
		(property "Datasheet" "https://www.murata.com/products/productdetail?partno=GRM155R61H104KE14%23"
			(at 88.9 199.39 0)
			(effects
				(font
					(size 1.27 1.27)
					(thickness 0.15)
				)
				(justify left bottom)
				(hide yes)
			)
		)
		(property "Description" ""
			(at 73.66 219.71 0)
			(effects
				(font
					(size 1.27 1.27)
				)
			)
		)
		(property "MPN" "GRM155R61H104KE14D"
			(at 91.44 199.39 0)
			(effects
				(font
					(size 1.27 1.27)
					(thickness 0.15)
				)
				(justify left bottom)
				(hide yes)
			)
		)
		(property "Manufacturer" "Murata"
			(at 93.98 199.39 0)
			(effects
				(font
					(size 1.27 1.27)
					(thickness 0.15)
				)
				(justify left bottom)
				(hide yes)
			)
		)
		(property "License" "Apache-2.0"
			(at 96.52 199.39 0)
			(effects
				(font
					(size 1.27 1.27)
					(thickness 0.15)
				)
				(justify left bottom)
				(hide yes)
			)
		)
		(property "Author" "Antmicro"
			(at 99.06 199.39 0)
			(effects
				(font
					(size 1.27 1.27)
					(thickness 0.15)
				)
				(justify left bottom)
				(hide yes)
			)
		)
		(property "Val" "100n"
			(at 74.295 219.075 90)
			(effects
				(font
					(size 1.27 1.27)
					(thickness 0.15)
				)
				(justify right)
			)
		)
		(property "Voltage" "50V"
			(at 101.6 199.39 0)
			(effects
				(font
					(size 1.27 1.27)
				)
				(justify left bottom)
				(hide yes)
			)
		)
		(property "Dielectric" "X5R"
			(at 104.14 199.39 0)
			(effects
				(font
					(size 1.27 1.27)
				)
				(justify left bottom)
				(hide yes)
			)
		)
		(pin "1"
		)
		(pin "2"
		)
		(instances
			(project "sodimm-ddr5-tester"
				(path ""
					(reference "C47")
					(unit 1)
				)
			)
		)
	)
	(symbol
		(lib_id "antmicropower:GND")
		(at 46.99 123.825 0)
		(mirror y)
		(unit 1)
		(exclude_from_sim no)
		(in_bom yes)
		(on_board yes)
		(dnp no)
		(fields_autoplaced yes)
		(property "Reference" "#PWR065"
			(at 46.99 130.175 0)
			(effects
				(font
					(size 1.27 1.27)
				)
				(hide yes)
			)
		)
		(property "Value" "GND"
			(at 49.53 125.095 0)
			(effects
				(font
					(size 1.27 1.27)
					(thickness 0.15)
				)
				(justify right)
			)
		)
		(property "Footprint" ""
			(at 38.1 131.445 0)
			(effects
				(font
					(size 1.27 1.27)
					(thickness 0.15)
				)
				(justify left bottom)
				(hide yes)
			)
		)
		(property "Datasheet" ""
			(at 38.1 136.525 0)
			(effects
				(font
					(size 1.27 1.27)
					(thickness 0.15)
				)
				(justify left bottom)
				(hide yes)
			)
		)
		(property "Description" ""
			(at 38.1 139.065 0)
			(effects
				(font
					(size 1.27 1.27)
				)
				(justify left bottom)
				(hide yes)
			)
		)
		(property "Author" "Antmicro"
			(at 38.1 131.445 0)
			(effects
				(font
					(size 1.27 1.27)
					(thickness 0.15)
				)
				(justify left bottom)
				(hide yes)
			)
		)
		(property "License" "Apache-2.0"
			(at 38.1 133.985 0)
			(effects
				(font
					(size 1.27 1.27)
					(thickness 0.15)
				)
				(justify left bottom)
				(hide yes)
			)
		)
		(pin "1"
		)
		(instances
			(project "sodimm-ddr5-tester"
				(path ""
					(reference "#PWR065")
					(unit 1)
				)
			)
		)
	)
	(symbol
		(lib_id "antmicroCapacitors0402:C_100n_0402")
		(at 337.185 125.73 90)
		(unit 1)
		(exclude_from_sim no)
		(in_bom yes)
		(on_board yes)
		(dnp no)
		(property "Reference" "C104"
			(at 337.82 121.285 90)
			(effects
				(font
					(size 1.27 1.27)
					(thickness 0.15)
				)
				(justify right)
			)
		)
		(property "Value" "C_100n_0402"
			(at 347.345 105.41 0)
			(effects
				(font
					(size 1.27 1.27)
					(thickness 0.15)
				)
				(justify left bottom)
				(hide yes)
			)
		)
		(property "Footprint" "antmicro-footprints:C_0402_1005Metric"
			(at 349.885 105.41 0)
			(effects
				(font
					(size 1.27 1.27)
					(thickness 0.15)
				)
				(justify left bottom)
				(hide yes)
			)
		)
		(property "Datasheet" "https://www.murata.com/products/productdetail?partno=GRM155R61H104KE14%23"
			(at 352.425 105.41 0)
			(effects
				(font
					(size 1.27 1.27)
					(thickness 0.15)
				)
				(justify left bottom)
				(hide yes)
			)
		)
		(property "Description" ""
			(at 337.185 125.73 0)
			(effects
				(font
					(size 1.27 1.27)
				)
			)
		)
		(property "MPN" "GRM155R61H104KE14D"
			(at 354.965 105.41 0)
			(effects
				(font
					(size 1.27 1.27)
					(thickness 0.15)
				)
				(justify left bottom)
				(hide yes)
			)
		)
		(property "Manufacturer" "Murata"
			(at 357.505 105.41 0)
			(effects
				(font
					(size 1.27 1.27)
					(thickness 0.15)
				)
				(justify left bottom)
				(hide yes)
			)
		)
		(property "License" "Apache-2.0"
			(at 360.045 105.41 0)
			(effects
				(font
					(size 1.27 1.27)
					(thickness 0.15)
				)
				(justify left bottom)
				(hide yes)
			)
		)
		(property "Author" "Antmicro"
			(at 362.585 105.41 0)
			(effects
				(font
					(size 1.27 1.27)
					(thickness 0.15)
				)
				(justify left bottom)
				(hide yes)
			)
		)
		(property "Val" "100n"
			(at 337.82 125.095 90)
			(effects
				(font
					(size 1.27 1.27)
					(thickness 0.15)
				)
				(justify right)
			)
		)
		(property "Voltage" "50V"
			(at 365.125 105.41 0)
			(effects
				(font
					(size 1.27 1.27)
				)
				(justify left bottom)
				(hide yes)
			)
		)
		(property "Dielectric" "X5R"
			(at 367.665 105.41 0)
			(effects
				(font
					(size 1.27 1.27)
				)
				(justify left bottom)
				(hide yes)
			)
		)
		(pin "1"
		)
		(pin "2"
		)
		(instances
			(project "sodimm-ddr5-tester"
				(path ""
					(reference "C104")
					(unit 1)
				)
			)
		)
	)
	(symbol
		(lib_id "antmicropower:+1V8")
		(at 38.735 112.395 0)
		(unit 1)
		(exclude_from_sim no)
		(in_bom yes)
		(on_board yes)
		(dnp no)
		(fields_autoplaced yes)
		(property "Reference" "#PWR051"
			(at 38.735 116.205 0)
			(effects
				(font
					(size 1.27 1.27)
				)
				(hide yes)
			)
		)
		(property "Value" "+1V8"
			(at 35.56 109.855 0)
			(effects
				(font
					(size 1.27 1.27)
					(thickness 0.15)
				)
				(justify left bottom)
			)
		)
		(property "Footprint" ""
			(at 53.975 120.015 0)
			(effects
				(font
					(size 1.27 1.27)
					(thickness 0.15)
				)
				(justify left bottom)
				(hide yes)
			)
		)
		(property "Datasheet" ""
			(at 53.975 122.555 0)
			(effects
				(font
					(size 1.27 1.27)
					(thickness 0.15)
				)
				(justify left bottom)
				(hide yes)
			)
		)
		(property "Description" ""
			(at 38.735 112.395 0)
			(effects
				(font
					(size 1.27 1.27)
				)
			)
		)
		(property "Author" "Antmicro"
			(at 53.975 117.475 0)
			(effects
				(font
					(size 1.27 1.27)
					(thickness 0.15)
				)
				(justify left bottom)
				(hide yes)
			)
		)
		(property "License" "Apache-2.0"
			(at 53.975 120.015 0)
			(effects
				(font
					(size 1.27 1.27)
					(thickness 0.15)
				)
				(justify left bottom)
				(hide yes)
			)
		)
		(pin "1"
		)
		(instances
			(project "sodimm-ddr5-tester"
				(path ""
					(reference "#PWR051")
					(unit 1)
				)
			)
		)
	)
	(symbol
		(lib_id "antmicropower:GND")
		(at 356.235 63.5 0)
		(unit 1)
		(exclude_from_sim no)
		(in_bom yes)
		(on_board yes)
		(dnp no)
		(fields_autoplaced yes)
		(property "Reference" "#PWR0156"
			(at 356.235 69.85 0)
			(effects
				(font
					(size 1.27 1.27)
				)
				(hide yes)
			)
		)
		(property "Value" "GND"
			(at 358.14 64.77 0)
			(effects
				(font
					(size 1.27 1.27)
					(thickness 0.15)
				)
				(justify left)
			)
		)
		(property "Footprint" ""
			(at 365.125 71.12 0)
			(effects
				(font
					(size 1.27 1.27)
					(thickness 0.15)
				)
				(justify left bottom)
				(hide yes)
			)
		)
		(property "Datasheet" ""
			(at 365.125 76.2 0)
			(effects
				(font
					(size 1.27 1.27)
					(thickness 0.15)
				)
				(justify left bottom)
				(hide yes)
			)
		)
		(property "Description" ""
			(at 365.125 78.74 0)
			(effects
				(font
					(size 1.27 1.27)
				)
				(justify left bottom)
				(hide yes)
			)
		)
		(property "Author" "Antmicro"
			(at 365.125 71.12 0)
			(effects
				(font
					(size 1.27 1.27)
					(thickness 0.15)
				)
				(justify left bottom)
				(hide yes)
			)
		)
		(property "License" "Apache-2.0"
			(at 365.125 73.66 0)
			(effects
				(font
					(size 1.27 1.27)
					(thickness 0.15)
				)
				(justify left bottom)
				(hide yes)
			)
		)
		(pin "1"
		)
		(instances
			(project "sodimm-ddr5-tester"
				(path ""
					(reference "#PWR0156")
					(unit 1)
				)
			)
		)
	)
	(symbol
		(lib_id "antmicropower:PWR_FLAG")
		(at 288.925 103.505 180)
		(unit 1)
		(exclude_from_sim no)
		(in_bom yes)
		(on_board yes)
		(dnp no)
		(property "Reference" "#FLG0119"
			(at 288.925 105.41 0)
			(effects
				(font
					(size 1.27 1.27)
				)
				(hide yes)
			)
		)
		(property "Value" "PWR_FLAG"
			(at 281.94 107.315 0)
			(effects
				(font
					(size 1.27 1.27)
				)
				(justify right)
			)
		)
		(property "Footprint" ""
			(at 288.925 103.505 0)
			(effects
				(font
					(size 1.27 1.27)
				)
				(hide yes)
			)
		)
		(property "Datasheet" ""
			(at 288.925 103.505 0)
			(effects
				(font
					(size 1.27 1.27)
				)
				(hide yes)
			)
		)
		(property "Description" ""
			(at 288.925 103.505 0)
			(effects
				(font
					(size 1.27 1.27)
				)
			)
		)
		(pin "1"
		)
		(instances
			(project "sodimm-ddr5-tester"
				(path ""
					(reference "#FLG0119")
					(unit 1)
				)
			)
		)
	)
	(symbol
		(lib_id "antmicroCapacitors0603:C_47u_0603")
		(at 116.205 155.575 270)
		(unit 1)
		(exclude_from_sim no)
		(in_bom yes)
		(on_board yes)
		(dnp no)
		(property "Reference" "C14"
			(at 116.205 156.21 90)
			(effects
				(font
					(size 1.27 1.27)
				)
				(justify left)
			)
		)
		(property "Value" "C_47u_0603"
			(at 106.045 175.895 0)
			(effects
				(font
					(size 1.27 1.27)
					(thickness 0.15)
				)
				(justify left bottom)
				(hide yes)
			)
		)
		(property "Footprint" "antmicro-footprints:C_0603_1608Metric"
			(at 103.505 175.895 0)
			(effects
				(font
					(size 1.27 1.27)
					(thickness 0.15)
				)
				(justify left bottom)
				(hide yes)
			)
		)
		(property "Datasheet" "https://www.murata.com/products/productdetail?partno=GRM188R60J476ME15%23"
			(at 100.965 175.895 0)
			(effects
				(font
					(size 1.27 1.27)
					(thickness 0.15)
				)
				(justify left bottom)
				(hide yes)
			)
		)
		(property "Description" ""
			(at 116.205 155.575 0)
			(effects
				(font
					(size 1.27 1.27)
				)
			)
		)
		(property "Manufacturer" "Murata"
			(at 95.885 175.895 0)
			(effects
				(font
					(size 1.27 1.27)
					(thickness 0.15)
				)
				(justify left bottom)
				(hide yes)
			)
		)
		(property "MPN" "GRM188R60J476ME15D"
			(at 98.425 175.895 0)
			(effects
				(font
					(size 1.27 1.27)
					(thickness 0.15)
				)
				(justify left bottom)
				(hide yes)
			)
		)
		(property "Val" "47u"
			(at 116.205 160.02 90)
			(effects
				(font
					(size 1.27 1.27)
					(thickness 0.15)
				)
				(justify left)
			)
		)
		(property "License" "Apache-2.0"
			(at 93.345 175.895 0)
			(effects
				(font
					(size 1.27 1.27)
					(thickness 0.15)
				)
				(justify left bottom)
				(hide yes)
			)
		)
		(property "Author" "Antmicro"
			(at 90.805 175.895 0)
			(effects
				(font
					(size 1.27 1.27)
					(thickness 0.15)
				)
				(justify left bottom)
				(hide yes)
			)
		)
		(property "Voltage" ""
			(at 88.265 175.895 0)
			(effects
				(font
					(size 1.27 1.27)
				)
				(justify left bottom)
				(hide yes)
			)
		)
		(property "Dielectric" ""
			(at 85.725 175.895 0)
			(effects
				(font
					(size 1.27 1.27)
				)
				(justify left bottom)
				(hide yes)
			)
		)
		(pin "1"
		)
		(pin "2"
		)
		(instances
			(project "sodimm-ddr5-tester"
				(path ""
					(reference "C14")
					(unit 1)
				)
			)
		)
	)
	(symbol
		(lib_id "antmicropower:GND")
		(at 106.045 94.615 0)
		(unit 1)
		(exclude_from_sim no)
		(in_bom yes)
		(on_board yes)
		(dnp no)
		(fields_autoplaced yes)
		(property "Reference" "#PWR0113"
			(at 106.045 100.965 0)
			(effects
				(font
					(size 1.27 1.27)
				)
				(hide yes)
			)
		)
		(property "Value" "GND"
			(at 107.95 95.885 0)
			(effects
				(font
					(size 1.27 1.27)
					(thickness 0.15)
				)
				(justify left)
			)
		)
		(property "Footprint" ""
			(at 114.935 102.235 0)
			(effects
				(font
					(size 1.27 1.27)
					(thickness 0.15)
				)
				(justify left bottom)
				(hide yes)
			)
		)
		(property "Datasheet" ""
			(at 114.935 107.315 0)
			(effects
				(font
					(size 1.27 1.27)
					(thickness 0.15)
				)
				(justify left bottom)
				(hide yes)
			)
		)
		(property "Description" ""
			(at 114.935 109.855 0)
			(effects
				(font
					(size 1.27 1.27)
				)
				(justify left bottom)
				(hide yes)
			)
		)
		(property "Author" "Antmicro"
			(at 114.935 102.235 0)
			(effects
				(font
					(size 1.27 1.27)
					(thickness 0.15)
				)
				(justify left bottom)
				(hide yes)
			)
		)
		(property "License" "Apache-2.0"
			(at 114.935 104.775 0)
			(effects
				(font
					(size 1.27 1.27)
					(thickness 0.15)
				)
				(justify left bottom)
				(hide yes)
			)
		)
		(pin "1"
		)
		(instances
			(project "sodimm-ddr5-tester"
				(path ""
					(reference "#PWR0113")
					(unit 1)
				)
			)
		)
	)
	(symbol
		(lib_id "antmicropower:+3V3")
		(at 38.735 180.34 0)
		(unit 1)
		(exclude_from_sim no)
		(in_bom yes)
		(on_board yes)
		(dnp no)
		(fields_autoplaced yes)
		(property "Reference" "#PWR061"
			(at 38.735 184.15 0)
			(effects
				(font
					(size 1.27 1.27)
				)
				(hide yes)
			)
		)
		(property "Value" "+3V3"
			(at 35.56 177.8 0)
			(effects
				(font
					(size 1.27 1.27)
					(thickness 0.15)
				)
				(justify left bottom)
			)
		)
		(property "Footprint" ""
			(at 53.975 187.96 0)
			(effects
				(font
					(size 1.27 1.27)
					(thickness 0.15)
				)
				(justify left bottom)
				(hide yes)
			)
		)
		(property "Datasheet" ""
			(at 53.975 190.5 0)
			(effects
				(font
					(size 1.27 1.27)
					(thickness 0.15)
				)
				(justify left bottom)
				(hide yes)
			)
		)
		(property "Description" ""
			(at 38.735 180.34 0)
			(effects
				(font
					(size 1.27 1.27)
				)
			)
		)
		(property "Author" "Antmicro"
			(at 53.975 182.88 0)
			(effects
				(font
					(size 1.27 1.27)
					(thickness 0.15)
				)
				(justify left bottom)
				(hide yes)
			)
		)
		(property "License" "Apache-2.0"
			(at 53.975 185.42 0)
			(effects
				(font
					(size 1.27 1.27)
					(thickness 0.15)
				)
				(justify left bottom)
				(hide yes)
			)
		)
		(pin "1"
		)
		(instances
			(project "sodimm-ddr5-tester"
				(path ""
					(reference "#PWR061")
					(unit 1)
				)
			)
		)
	)
	(symbol
		(lib_id "antmicroCapacitors0402:C_100n_0402")
		(at 356.235 62.23 90)
		(unit 1)
		(exclude_from_sim no)
		(in_bom yes)
		(on_board yes)
		(dnp no)
		(property "Reference" "C100"
			(at 356.87 57.785 90)
			(effects
				(font
					(size 1.27 1.27)
					(thickness 0.15)
				)
				(justify right)
			)
		)
		(property "Value" "C_100n_0402"
			(at 366.395 41.91 0)
			(effects
				(font
					(size 1.27 1.27)
					(thickness 0.15)
				)
				(justify left bottom)
				(hide yes)
			)
		)
		(property "Footprint" "antmicro-footprints:C_0402_1005Metric"
			(at 368.935 41.91 0)
			(effects
				(font
					(size 1.27 1.27)
					(thickness 0.15)
				)
				(justify left bottom)
				(hide yes)
			)
		)
		(property "Datasheet" "https://www.murata.com/products/productdetail?partno=GRM155R61H104KE14%23"
			(at 371.475 41.91 0)
			(effects
				(font
					(size 1.27 1.27)
					(thickness 0.15)
				)
				(justify left bottom)
				(hide yes)
			)
		)
		(property "Description" ""
			(at 356.235 62.23 0)
			(effects
				(font
					(size 1.27 1.27)
				)
			)
		)
		(property "MPN" "GRM155R61H104KE14D"
			(at 374.015 41.91 0)
			(effects
				(font
					(size 1.27 1.27)
					(thickness 0.15)
				)
				(justify left bottom)
				(hide yes)
			)
		)
		(property "Manufacturer" "Murata"
			(at 376.555 41.91 0)
			(effects
				(font
					(size 1.27 1.27)
					(thickness 0.15)
				)
				(justify left bottom)
				(hide yes)
			)
		)
		(property "License" "Apache-2.0"
			(at 379.095 41.91 0)
			(effects
				(font
					(size 1.27 1.27)
					(thickness 0.15)
				)
				(justify left bottom)
				(hide yes)
			)
		)
		(property "Author" "Antmicro"
			(at 381.635 41.91 0)
			(effects
				(font
					(size 1.27 1.27)
					(thickness 0.15)
				)
				(justify left bottom)
				(hide yes)
			)
		)
		(property "Val" "100n"
			(at 356.87 61.595 90)
			(effects
				(font
					(size 1.27 1.27)
					(thickness 0.15)
				)
				(justify right)
			)
		)
		(property "Voltage" "50V"
			(at 384.175 41.91 0)
			(effects
				(font
					(size 1.27 1.27)
				)
				(justify left bottom)
				(hide yes)
			)
		)
		(property "Dielectric" "X5R"
			(at 386.715 41.91 0)
			(effects
				(font
					(size 1.27 1.27)
				)
				(justify left bottom)
				(hide yes)
			)
		)
		(pin "1"
		)
		(pin "2"
		)
		(instances
			(project "sodimm-ddr5-tester"
				(path ""
					(reference "C100")
					(unit 1)
				)
			)
		)
	)
	(symbol
		(lib_id "antmicroCapacitors0402:C_100n_0402")
		(at 55.88 93.345 90)
		(unit 1)
		(exclude_from_sim no)
		(in_bom yes)
		(on_board yes)
		(dnp no)
		(property "Reference" "C26"
			(at 56.515 88.9 90)
			(effects
				(font
					(size 1.27 1.27)
					(thickness 0.15)
				)
				(justify right)
			)
		)
		(property "Value" "C_100n_0402"
			(at 66.04 73.025 0)
			(effects
				(font
					(size 1.27 1.27)
					(thickness 0.15)
				)
				(justify left bottom)
				(hide yes)
			)
		)
		(property "Footprint" "antmicro-footprints:C_0402_1005Metric"
			(at 68.58 73.025 0)
			(effects
				(font
					(size 1.27 1.27)
					(thickness 0.15)
				)
				(justify left bottom)
				(hide yes)
			)
		)
		(property "Datasheet" "https://www.murata.com/products/productdetail?partno=GRM155R61H104KE14%23"
			(at 71.12 73.025 0)
			(effects
				(font
					(size 1.27 1.27)
					(thickness 0.15)
				)
				(justify left bottom)
				(hide yes)
			)
		)
		(property "Description" ""
			(at 55.88 93.345 0)
			(effects
				(font
					(size 1.27 1.27)
				)
			)
		)
		(property "MPN" "GRM155R61H104KE14D"
			(at 73.66 73.025 0)
			(effects
				(font
					(size 1.27 1.27)
					(thickness 0.15)
				)
				(justify left bottom)
				(hide yes)
			)
		)
		(property "Manufacturer" "Murata"
			(at 76.2 73.025 0)
			(effects
				(font
					(size 1.27 1.27)
					(thickness 0.15)
				)
				(justify left bottom)
				(hide yes)
			)
		)
		(property "License" "Apache-2.0"
			(at 78.74 73.025 0)
			(effects
				(font
					(size 1.27 1.27)
					(thickness 0.15)
				)
				(justify left bottom)
				(hide yes)
			)
		)
		(property "Author" "Antmicro"
			(at 81.28 73.025 0)
			(effects
				(font
					(size 1.27 1.27)
					(thickness 0.15)
				)
				(justify left bottom)
				(hide yes)
			)
		)
		(property "Val" "100n"
			(at 56.515 92.71 90)
			(effects
				(font
					(size 1.27 1.27)
					(thickness 0.15)
				)
				(justify right)
			)
		)
		(property "Voltage" "50V"
			(at 83.82 73.025 0)
			(effects
				(font
					(size 1.27 1.27)
				)
				(justify left bottom)
				(hide yes)
			)
		)
		(property "Dielectric" "X5R"
			(at 86.36 73.025 0)
			(effects
				(font
					(size 1.27 1.27)
				)
				(justify left bottom)
				(hide yes)
			)
		)
		(pin "1"
		)
		(pin "2"
		)
		(instances
			(project "sodimm-ddr5-tester"
				(path ""
					(reference "C26")
					(unit 1)
				)
			)
		)
	)
	(symbol
		(lib_id "antmicropower:GND")
		(at 57.15 68.58 0)
		(mirror y)
		(unit 1)
		(exclude_from_sim no)
		(in_bom yes)
		(on_board yes)
		(dnp no)
		(fields_autoplaced yes)
		(property "Reference" "#PWR072"
			(at 57.15 74.93 0)
			(effects
				(font
					(size 1.27 1.27)
				)
				(hide yes)
			)
		)
		(property "Value" "GND"
			(at 59.69 69.85 0)
			(effects
				(font
					(size 1.27 1.27)
					(thickness 0.15)
				)
				(justify right)
			)
		)
		(property "Footprint" ""
			(at 48.26 76.2 0)
			(effects
				(font
					(size 1.27 1.27)
					(thickness 0.15)
				)
				(justify left bottom)
				(hide yes)
			)
		)
		(property "Datasheet" ""
			(at 48.26 81.28 0)
			(effects
				(font
					(size 1.27 1.27)
					(thickness 0.15)
				)
				(justify left bottom)
				(hide yes)
			)
		)
		(property "Description" ""
			(at 48.26 83.82 0)
			(effects
				(font
					(size 1.27 1.27)
				)
				(justify left bottom)
				(hide yes)
			)
		)
		(property "Author" "Antmicro"
			(at 48.26 76.2 0)
			(effects
				(font
					(size 1.27 1.27)
					(thickness 0.15)
				)
				(justify left bottom)
				(hide yes)
			)
		)
		(property "License" "Apache-2.0"
			(at 48.26 78.74 0)
			(effects
				(font
					(size 1.27 1.27)
					(thickness 0.15)
				)
				(justify left bottom)
				(hide yes)
			)
		)
		(pin "1"
		)
		(instances
			(project "sodimm-ddr5-tester"
				(path ""
					(reference "#PWR072")
					(unit 1)
				)
			)
		)
	)
	(symbol
		(lib_id "antmicropower:GND")
		(at 133.35 124.46 0)
		(unit 1)
		(exclude_from_sim no)
		(in_bom yes)
		(on_board yes)
		(dnp no)
		(fields_autoplaced yes)
		(property "Reference" "#PWR0130"
			(at 133.35 130.81 0)
			(effects
				(font
					(size 1.27 1.27)
				)
				(hide yes)
			)
		)
		(property "Value" "GND"
			(at 135.89 125.73 0)
			(effects
				(font
					(size 1.27 1.27)
					(thickness 0.15)
				)
				(justify left)
			)
		)
		(property "Footprint" ""
			(at 142.24 132.08 0)
			(effects
				(font
					(size 1.27 1.27)
					(thickness 0.15)
				)
				(justify left bottom)
				(hide yes)
			)
		)
		(property "Datasheet" ""
			(at 142.24 137.16 0)
			(effects
				(font
					(size 1.27 1.27)
					(thickness 0.15)
				)
				(justify left bottom)
				(hide yes)
			)
		)
		(property "Description" ""
			(at 142.24 139.7 0)
			(effects
				(font
					(size 1.27 1.27)
				)
				(justify left bottom)
				(hide yes)
			)
		)
		(property "Author" "Antmicro"
			(at 142.24 132.08 0)
			(effects
				(font
					(size 1.27 1.27)
					(thickness 0.15)
				)
				(justify left bottom)
				(hide yes)
			)
		)
		(property "License" "Apache-2.0"
			(at 142.24 134.62 0)
			(effects
				(font
					(size 1.27 1.27)
					(thickness 0.15)
				)
				(justify left bottom)
				(hide yes)
			)
		)
		(pin "1"
		)
		(instances
			(project "sodimm-ddr5-tester"
				(path ""
					(reference "#PWR0130")
					(unit 1)
				)
			)
		)
	)
	(symbol
		(lib_id "antmicroCapacitors0402:C_100n_0402")
		(at 133.35 122.555 90)
		(unit 1)
		(exclude_from_sim no)
		(in_bom yes)
		(on_board yes)
		(dnp no)
		(property "Reference" "C81"
			(at 133.985 118.11 90)
			(effects
				(font
					(size 1.27 1.27)
					(thickness 0.15)
				)
				(justify right)
			)
		)
		(property "Value" "C_100n_0402"
			(at 143.51 102.235 0)
			(effects
				(font
					(size 1.27 1.27)
					(thickness 0.15)
				)
				(justify left bottom)
				(hide yes)
			)
		)
		(property "Footprint" "antmicro-footprints:C_0402_1005Metric"
			(at 146.05 102.235 0)
			(effects
				(font
					(size 1.27 1.27)
					(thickness 0.15)
				)
				(justify left bottom)
				(hide yes)
			)
		)
		(property "Datasheet" "https://www.murata.com/products/productdetail?partno=GRM155R61H104KE14%23"
			(at 148.59 102.235 0)
			(effects
				(font
					(size 1.27 1.27)
					(thickness 0.15)
				)
				(justify left bottom)
				(hide yes)
			)
		)
		(property "Description" ""
			(at 133.35 122.555 0)
			(effects
				(font
					(size 1.27 1.27)
				)
			)
		)
		(property "MPN" "GRM155R61H104KE14D"
			(at 151.13 102.235 0)
			(effects
				(font
					(size 1.27 1.27)
					(thickness 0.15)
				)
				(justify left bottom)
				(hide yes)
			)
		)
		(property "Manufacturer" "Murata"
			(at 153.67 102.235 0)
			(effects
				(font
					(size 1.27 1.27)
					(thickness 0.15)
				)
				(justify left bottom)
				(hide yes)
			)
		)
		(property "License" "Apache-2.0"
			(at 156.21 102.235 0)
			(effects
				(font
					(size 1.27 1.27)
					(thickness 0.15)
				)
				(justify left bottom)
				(hide yes)
			)
		)
		(property "Author" "Antmicro"
			(at 158.75 102.235 0)
			(effects
				(font
					(size 1.27 1.27)
					(thickness 0.15)
				)
				(justify left bottom)
				(hide yes)
			)
		)
		(property "Val" "100n"
			(at 133.985 121.92 90)
			(effects
				(font
					(size 1.27 1.27)
					(thickness 0.15)
				)
				(justify right)
			)
		)
		(property "Voltage" "50V"
			(at 161.29 102.235 0)
			(effects
				(font
					(size 1.27 1.27)
				)
				(justify left bottom)
				(hide yes)
			)
		)
		(property "Dielectric" "X5R"
			(at 163.83 102.235 0)
			(effects
				(font
					(size 1.27 1.27)
				)
				(justify left bottom)
				(hide yes)
			)
		)
		(pin "1"
		)
		(pin "2"
		)
		(instances
			(project "sodimm-ddr5-tester"
				(path ""
					(reference "C81")
					(unit 1)
				)
			)
		)
	)
	(symbol
		(lib_id "antmicroCapacitors0402:C_100n_0402")
		(at 122.555 220.345 90)
		(unit 1)
		(exclude_from_sim no)
		(in_bom yes)
		(on_board yes)
		(dnp no)
		(property "Reference" "C87"
			(at 127 215.9 90)
			(effects
				(font
					(size 1.27 1.27)
					(thickness 0.15)
				)
				(justify left)
			)
		)
		(property "Value" "C_100n_0402"
			(at 132.715 200.025 0)
			(effects
				(font
					(size 1.27 1.27)
					(thickness 0.15)
				)
				(justify left bottom)
				(hide yes)
			)
		)
		(property "Footprint" "antmicro-footprints:C_0402_1005Metric"
			(at 135.255 200.025 0)
			(effects
				(font
					(size 1.27 1.27)
					(thickness 0.15)
				)
				(justify left bottom)
				(hide yes)
			)
		)
		(property "Datasheet" "https://www.murata.com/products/productdetail?partno=GRM155R61H104KE14%23"
			(at 137.795 200.025 0)
			(effects
				(font
					(size 1.27 1.27)
					(thickness 0.15)
				)
				(justify left bottom)
				(hide yes)
			)
		)
		(property "Description" ""
			(at 122.555 220.345 0)
			(effects
				(font
					(size 1.27 1.27)
				)
			)
		)
		(property "MPN" "GRM155R61H104KE14D"
			(at 140.335 200.025 0)
			(effects
				(font
					(size 1.27 1.27)
					(thickness 0.15)
				)
				(justify left bottom)
				(hide yes)
			)
		)
		(property "Manufacturer" "Murata"
			(at 142.875 200.025 0)
			(effects
				(font
					(size 1.27 1.27)
					(thickness 0.15)
				)
				(justify left bottom)
				(hide yes)
			)
		)
		(property "License" "Apache-2.0"
			(at 145.415 200.025 0)
			(effects
				(font
					(size 1.27 1.27)
					(thickness 0.15)
				)
				(justify left bottom)
				(hide yes)
			)
		)
		(property "Author" "Antmicro"
			(at 147.955 200.025 0)
			(effects
				(font
					(size 1.27 1.27)
					(thickness 0.15)
				)
				(justify left bottom)
				(hide yes)
			)
		)
		(property "Val" "100n"
			(at 128.27 219.71 90)
			(effects
				(font
					(size 1.27 1.27)
					(thickness 0.15)
				)
				(justify left)
			)
		)
		(property "Voltage" "50V"
			(at 150.495 200.025 0)
			(effects
				(font
					(size 1.27 1.27)
				)
				(justify left bottom)
				(hide yes)
			)
		)
		(property "Dielectric" "X5R"
			(at 153.035 200.025 0)
			(effects
				(font
					(size 1.27 1.27)
				)
				(justify left bottom)
				(hide yes)
			)
		)
		(pin "1"
		)
		(pin "2"
		)
		(instances
			(project "sodimm-ddr5-tester"
				(path ""
					(reference "C87")
					(unit 1)
				)
			)
		)
	)
	(symbol
		(lib_id "antmicropower:GND")
		(at 136.525 222.25 0)
		(unit 1)
		(exclude_from_sim no)
		(in_bom yes)
		(on_board yes)
		(dnp no)
		(fields_autoplaced yes)
		(property "Reference" "#PWR0141"
			(at 136.525 228.6 0)
			(effects
				(font
					(size 1.27 1.27)
				)
				(hide yes)
			)
		)
		(property "Value" "GND"
			(at 138.43 223.52 0)
			(effects
				(font
					(size 1.27 1.27)
					(thickness 0.15)
				)
				(justify left)
			)
		)
		(property "Footprint" ""
			(at 145.415 229.87 0)
			(effects
				(font
					(size 1.27 1.27)
					(thickness 0.15)
				)
				(justify left bottom)
				(hide yes)
			)
		)
		(property "Datasheet" ""
			(at 145.415 234.95 0)
			(effects
				(font
					(size 1.27 1.27)
					(thickness 0.15)
				)
				(justify left bottom)
				(hide yes)
			)
		)
		(property "Description" ""
			(at 145.415 237.49 0)
			(effects
				(font
					(size 1.27 1.27)
				)
				(justify left bottom)
				(hide yes)
			)
		)
		(property "Author" "Antmicro"
			(at 145.415 229.87 0)
			(effects
				(font
					(size 1.27 1.27)
					(thickness 0.15)
				)
				(justify left bottom)
				(hide yes)
			)
		)
		(property "License" "Apache-2.0"
			(at 145.415 232.41 0)
			(effects
				(font
					(size 1.27 1.27)
					(thickness 0.15)
				)
				(justify left bottom)
				(hide yes)
			)
		)
		(pin "1"
		)
		(instances
			(project "sodimm-ddr5-tester"
				(path ""
					(reference "#PWR0141")
					(unit 1)
				)
			)
		)
	)
	(symbol
		(lib_id "antmicropower:GND")
		(at 130.175 162.56 0)
		(unit 1)
		(exclude_from_sim no)
		(in_bom yes)
		(on_board yes)
		(dnp no)
		(fields_autoplaced yes)
		(property "Reference" "#PWR071"
			(at 130.175 168.91 0)
			(effects
				(font
					(size 1.27 1.27)
				)
				(hide yes)
			)
		)
		(property "Value" "GND"
			(at 132.08 163.83 0)
			(effects
				(font
					(size 1.27 1.27)
					(thickness 0.15)
				)
				(justify left)
			)
		)
		(property "Footprint" ""
			(at 139.065 170.18 0)
			(effects
				(font
					(size 1.27 1.27)
					(thickness 0.15)
				)
				(justify left bottom)
				(hide yes)
			)
		)
		(property "Datasheet" ""
			(at 139.065 175.26 0)
			(effects
				(font
					(size 1.27 1.27)
					(thickness 0.15)
				)
				(justify left bottom)
				(hide yes)
			)
		)
		(property "Description" ""
			(at 139.065 177.8 0)
			(effects
				(font
					(size 1.27 1.27)
				)
				(justify left bottom)
				(hide yes)
			)
		)
		(property "Author" "Antmicro"
			(at 139.065 170.18 0)
			(effects
				(font
					(size 1.27 1.27)
					(thickness 0.15)
				)
				(justify left bottom)
				(hide yes)
			)
		)
		(property "License" "Apache-2.0"
			(at 139.065 172.72 0)
			(effects
				(font
					(size 1.27 1.27)
					(thickness 0.15)
				)
				(justify left bottom)
				(hide yes)
			)
		)
		(pin "1"
		)
		(instances
			(project "sodimm-ddr5-tester"
				(path ""
					(reference "#PWR071")
					(unit 1)
				)
			)
		)
	)
	(symbol
		(lib_id "antmicropower:GND")
		(at 115.57 222.25 0)
		(unit 1)
		(exclude_from_sim no)
		(in_bom yes)
		(on_board yes)
		(dnp no)
		(fields_autoplaced yes)
		(property "Reference" "#PWR0135"
			(at 115.57 228.6 0)
			(effects
				(font
					(size 1.27 1.27)
				)
				(hide yes)
			)
		)
		(property "Value" "GND"
			(at 118.11 223.52 0)
			(effects
				(font
					(size 1.27 1.27)
					(thickness 0.15)
				)
				(justify left)
			)
		)
		(property "Footprint" ""
			(at 124.46 229.87 0)
			(effects
				(font
					(size 1.27 1.27)
					(thickness 0.15)
				)
				(justify left bottom)
				(hide yes)
			)
		)
		(property "Datasheet" ""
			(at 124.46 234.95 0)
			(effects
				(font
					(size 1.27 1.27)
					(thickness 0.15)
				)
				(justify left bottom)
				(hide yes)
			)
		)
		(property "Description" ""
			(at 124.46 237.49 0)
			(effects
				(font
					(size 1.27 1.27)
				)
				(justify left bottom)
				(hide yes)
			)
		)
		(property "Author" "Antmicro"
			(at 124.46 229.87 0)
			(effects
				(font
					(size 1.27 1.27)
					(thickness 0.15)
				)
				(justify left bottom)
				(hide yes)
			)
		)
		(property "License" "Apache-2.0"
			(at 124.46 232.41 0)
			(effects
				(font
					(size 1.27 1.27)
					(thickness 0.15)
				)
				(justify left bottom)
				(hide yes)
			)
		)
		(pin "1"
		)
		(instances
			(project "sodimm-ddr5-tester"
				(path ""
					(reference "#PWR0135")
					(unit 1)
				)
			)
		)
	)
	(symbol
		(lib_id "antmicroCapacitors0402:C_100n_0402")
		(at 73.025 247.65 90)
		(unit 1)
		(exclude_from_sim no)
		(in_bom yes)
		(on_board yes)
		(dnp no)
		(property "Reference" "C45"
			(at 73.66 243.205 90)
			(effects
				(font
					(size 1.27 1.27)
					(thickness 0.15)
				)
				(justify right)
			)
		)
		(property "Value" "C_100n_0402"
			(at 83.185 227.33 0)
			(effects
				(font
					(size 1.27 1.27)
					(thickness 0.15)
				)
				(justify left bottom)
				(hide yes)
			)
		)
		(property "Footprint" "antmicro-footprints:C_0402_1005Metric"
			(at 85.725 227.33 0)
			(effects
				(font
					(size 1.27 1.27)
					(thickness 0.15)
				)
				(justify left bottom)
				(hide yes)
			)
		)
		(property "Datasheet" "https://www.murata.com/products/productdetail?partno=GRM155R61H104KE14%23"
			(at 88.265 227.33 0)
			(effects
				(font
					(size 1.27 1.27)
					(thickness 0.15)
				)
				(justify left bottom)
				(hide yes)
			)
		)
		(property "Description" ""
			(at 73.025 247.65 0)
			(effects
				(font
					(size 1.27 1.27)
				)
			)
		)
		(property "MPN" "GRM155R61H104KE14D"
			(at 90.805 227.33 0)
			(effects
				(font
					(size 1.27 1.27)
					(thickness 0.15)
				)
				(justify left bottom)
				(hide yes)
			)
		)
		(property "Manufacturer" "Murata"
			(at 93.345 227.33 0)
			(effects
				(font
					(size 1.27 1.27)
					(thickness 0.15)
				)
				(justify left bottom)
				(hide yes)
			)
		)
		(property "License" "Apache-2.0"
			(at 95.885 227.33 0)
			(effects
				(font
					(size 1.27 1.27)
					(thickness 0.15)
				)
				(justify left bottom)
				(hide yes)
			)
		)
		(property "Author" "Antmicro"
			(at 98.425 227.33 0)
			(effects
				(font
					(size 1.27 1.27)
					(thickness 0.15)
				)
				(justify left bottom)
				(hide yes)
			)
		)
		(property "Val" "100n"
			(at 73.66 247.015 90)
			(effects
				(font
					(size 1.27 1.27)
					(thickness 0.15)
				)
				(justify right)
			)
		)
		(property "Voltage" "50V"
			(at 100.965 227.33 0)
			(effects
				(font
					(size 1.27 1.27)
				)
				(justify left bottom)
				(hide yes)
			)
		)
		(property "Dielectric" "X5R"
			(at 103.505 227.33 0)
			(effects
				(font
					(size 1.27 1.27)
				)
				(justify left bottom)
				(hide yes)
			)
		)
		(pin "1"
		)
		(pin "2"
		)
		(instances
			(project "sodimm-ddr5-tester"
				(path ""
					(reference "C45")
					(unit 1)
				)
			)
		)
	)
	(symbol
		(lib_id "antmicroCapacitorspol:C_Pol_1m_2.5V_KEMET-T520-D")
		(at 39.37 62.23 270)
		(unit 1)
		(exclude_from_sim no)
		(in_bom yes)
		(on_board yes)
		(dnp no)
		(fields_autoplaced yes)
		(property "Reference" "C12"
			(at 41.783 63.406 90)
			(effects
				(font
					(size 1.27 1.27)
					(thickness 0.15)
				)
				(justify left)
			)
		)
		(property "Value" "C_Pol_1m_2.5V_KEMET-T520-D"
			(at 36.83 76.2 0)
			(effects
				(font
					(size 1.27 1.27)
					(thickness 0.15)
				)
				(justify left bottom)
				(hide yes)
			)
		)
		(property "Footprint" "antmicro-footprints:C_Pol_EIA-D"
			(at 31.75 76.2 0)
			(effects
				(font
					(size 1.27 1.27)
					(thickness 0.15)
				)
				(justify left bottom)
				(hide yes)
			)
		)
		(property "Datasheet" "https://content.kemet.com/datasheets/KEM_T2076_T52X-530.pdf"
			(at 29.21 76.2 0)
			(effects
				(font
					(size 1.27 1.27)
					(thickness 0.15)
				)
				(justify left bottom)
				(hide yes)
			)
		)
		(property "Description" ""
			(at 39.37 62.23 0)
			(effects
				(font
					(size 1.27 1.27)
				)
			)
		)
		(property "MPN" "T520D108M2R5ATE030"
			(at 26.67 76.2 0)
			(effects
				(font
					(size 1.27 1.27)
					(thickness 0.15)
				)
				(justify left bottom)
				(hide yes)
			)
		)
		(property "Manufacturer" "KEMET"
			(at 24.13 76.2 0)
			(effects
				(font
					(size 1.27 1.27)
					(thickness 0.15)
				)
				(justify left bottom)
				(hide yes)
			)
		)
		(property "License" "Apache-2.0"
			(at 21.59 76.2 0)
			(effects
				(font
					(size 1.27 1.27)
					(thickness 0.15)
				)
				(justify left bottom)
				(hide yes)
			)
		)
		(property "Author" "Antmicro"
			(at 19.05 76.2 0)
			(effects
				(font
					(size 1.27 1.27)
					(thickness 0.15)
				)
				(justify left bottom)
				(hide yes)
			)
		)
		(property "Val" "1000u/2.5V"
			(at 41.783 65.9297 90)
			(effects
				(font
					(size 1.27 1.27)
					(thickness 0.15)
				)
				(justify left)
			)
		)
		(property "Voltage" "2.5V"
			(at 16.51 76.2 0)
			(effects
				(font
					(size 1.27 1.27)
				)
				(justify left bottom)
				(hide yes)
			)
		)
		(pin "1"
		)
		(pin "2"
		)
		(instances
			(project "sodimm-ddr5-tester"
				(path ""
					(reference "C12")
					(unit 1)
				)
			)
		)
	)
	(symbol
		(lib_id "antmicropower:GND")
		(at 47.625 94.615 0)
		(unit 1)
		(exclude_from_sim no)
		(in_bom yes)
		(on_board yes)
		(dnp no)
		(fields_autoplaced yes)
		(property "Reference" "#PWR066"
			(at 47.625 100.965 0)
			(effects
				(font
					(size 1.27 1.27)
				)
				(hide yes)
			)
		)
		(property "Value" "GND"
			(at 49.53 95.885 0)
			(effects
				(font
					(size 1.27 1.27)
					(thickness 0.15)
				)
				(justify left)
			)
		)
		(property "Footprint" ""
			(at 56.515 102.235 0)
			(effects
				(font
					(size 1.27 1.27)
					(thickness 0.15)
				)
				(justify left bottom)
				(hide yes)
			)
		)
		(property "Datasheet" ""
			(at 56.515 107.315 0)
			(effects
				(font
					(size 1.27 1.27)
					(thickness 0.15)
				)
				(justify left bottom)
				(hide yes)
			)
		)
		(property "Description" ""
			(at 56.515 109.855 0)
			(effects
				(font
					(size 1.27 1.27)
				)
				(justify left bottom)
				(hide yes)
			)
		)
		(property "Author" "Antmicro"
			(at 56.515 102.235 0)
			(effects
				(font
					(size 1.27 1.27)
					(thickness 0.15)
				)
				(justify left bottom)
				(hide yes)
			)
		)
		(property "License" "Apache-2.0"
			(at 56.515 104.775 0)
			(effects
				(font
					(size 1.27 1.27)
					(thickness 0.15)
				)
				(justify left bottom)
				(hide yes)
			)
		)
		(pin "1"
		)
		(instances
			(project "sodimm-ddr5-tester"
				(path ""
					(reference "#PWR066")
					(unit 1)
				)
			)
		)
	)
	(symbol
		(lib_id "antmicroCapacitors0603:C_47u_0603")
		(at 55.88 117.475 270)
		(unit 1)
		(exclude_from_sim no)
		(in_bom yes)
		(on_board yes)
		(dnp no)
		(property "Reference" "C27"
			(at 56.515 118.11 90)
			(effects
				(font
					(size 1.27 1.27)
				)
				(justify left)
			)
		)
		(property "Value" "C_47u_0603"
			(at 45.72 137.795 0)
			(effects
				(font
					(size 1.27 1.27)
					(thickness 0.15)
				)
				(justify left bottom)
				(hide yes)
			)
		)
		(property "Footprint" "antmicro-footprints:C_0603_1608Metric"
			(at 43.18 137.795 0)
			(effects
				(font
					(size 1.27 1.27)
					(thickness 0.15)
				)
				(justify left bottom)
				(hide yes)
			)
		)
		(property "Datasheet" "https://www.murata.com/products/productdetail?partno=GRM188R60J476ME15%23"
			(at 40.64 137.795 0)
			(effects
				(font
					(size 1.27 1.27)
					(thickness 0.15)
				)
				(justify left bottom)
				(hide yes)
			)
		)
		(property "Description" ""
			(at 55.88 117.475 0)
			(effects
				(font
					(size 1.27 1.27)
				)
			)
		)
		(property "Manufacturer" "Murata"
			(at 35.56 137.795 0)
			(effects
				(font
					(size 1.27 1.27)
					(thickness 0.15)
				)
				(justify left bottom)
				(hide yes)
			)
		)
		(property "MPN" "GRM188R60J476ME15D"
			(at 38.1 137.795 0)
			(effects
				(font
					(size 1.27 1.27)
					(thickness 0.15)
				)
				(justify left bottom)
				(hide yes)
			)
		)
		(property "Val" "47u"
			(at 56.515 121.92 90)
			(effects
				(font
					(size 1.27 1.27)
					(thickness 0.15)
				)
				(justify left)
			)
		)
		(property "License" "Apache-2.0"
			(at 33.02 137.795 0)
			(effects
				(font
					(size 1.27 1.27)
					(thickness 0.15)
				)
				(justify left bottom)
				(hide yes)
			)
		)
		(property "Author" "Antmicro"
			(at 30.48 137.795 0)
			(effects
				(font
					(size 1.27 1.27)
					(thickness 0.15)
				)
				(justify left bottom)
				(hide yes)
			)
		)
		(property "Voltage" ""
			(at 27.94 137.795 0)
			(effects
				(font
					(size 1.27 1.27)
				)
				(justify left bottom)
				(hide yes)
			)
		)
		(property "Dielectric" ""
			(at 25.4 137.795 0)
			(effects
				(font
					(size 1.27 1.27)
				)
				(justify left bottom)
				(hide yes)
			)
		)
		(pin "1"
		)
		(pin "2"
		)
		(instances
			(project "sodimm-ddr5-tester"
				(path ""
					(reference "C27")
					(unit 1)
				)
			)
		)
	)
	(symbol
		(lib_id "antmicropower:GND")
		(at 151.13 162.56 0)
		(unit 1)
		(exclude_from_sim no)
		(in_bom yes)
		(on_board yes)
		(dnp no)
		(fields_autoplaced yes)
		(property "Reference" "#PWR091"
			(at 151.13 168.91 0)
			(effects
				(font
					(size 1.27 1.27)
				)
				(hide yes)
			)
		)
		(property "Value" "GND"
			(at 153.67 163.83 0)
			(effects
				(font
					(size 1.27 1.27)
					(thickness 0.15)
				)
				(justify left)
			)
		)
		(property "Footprint" ""
			(at 160.02 170.18 0)
			(effects
				(font
					(size 1.27 1.27)
					(thickness 0.15)
				)
				(justify left bottom)
				(hide yes)
			)
		)
		(property "Datasheet" ""
			(at 160.02 175.26 0)
			(effects
				(font
					(size 1.27 1.27)
					(thickness 0.15)
				)
				(justify left bottom)
				(hide yes)
			)
		)
		(property "Description" ""
			(at 160.02 177.8 0)
			(effects
				(font
					(size 1.27 1.27)
				)
				(justify left bottom)
				(hide yes)
			)
		)
		(property "Author" "Antmicro"
			(at 160.02 170.18 0)
			(effects
				(font
					(size 1.27 1.27)
					(thickness 0.15)
				)
				(justify left bottom)
				(hide yes)
			)
		)
		(property "License" "Apache-2.0"
			(at 160.02 172.72 0)
			(effects
				(font
					(size 1.27 1.27)
					(thickness 0.15)
				)
				(justify left bottom)
				(hide yes)
			)
		)
		(pin "1"
		)
		(instances
			(project "sodimm-ddr5-tester"
				(path ""
					(reference "#PWR091")
					(unit 1)
				)
			)
		)
	)
	(symbol
		(lib_id "antmicropower:GND")
		(at 53.975 161.925 0)
		(unit 1)
		(exclude_from_sim no)
		(in_bom yes)
		(on_board yes)
		(dnp no)
		(fields_autoplaced yes)
		(property "Reference" "#PWR0129"
			(at 53.975 168.275 0)
			(effects
				(font
					(size 1.27 1.27)
				)
				(hide yes)
			)
		)
		(property "Value" "GND"
			(at 55.88 163.195 0)
			(effects
				(font
					(size 1.27 1.27)
					(thickness 0.15)
				)
				(justify left)
			)
		)
		(property "Footprint" ""
			(at 62.865 169.545 0)
			(effects
				(font
					(size 1.27 1.27)
					(thickness 0.15)
				)
				(justify left bottom)
				(hide yes)
			)
		)
		(property "Datasheet" ""
			(at 62.865 174.625 0)
			(effects
				(font
					(size 1.27 1.27)
					(thickness 0.15)
				)
				(justify left bottom)
				(hide yes)
			)
		)
		(property "Description" ""
			(at 62.865 177.165 0)
			(effects
				(font
					(size 1.27 1.27)
				)
				(justify left bottom)
				(hide yes)
			)
		)
		(property "Author" "Antmicro"
			(at 62.865 169.545 0)
			(effects
				(font
					(size 1.27 1.27)
					(thickness 0.15)
				)
				(justify left bottom)
				(hide yes)
			)
		)
		(property "License" "Apache-2.0"
			(at 62.865 172.085 0)
			(effects
				(font
					(size 1.27 1.27)
					(thickness 0.15)
				)
				(justify left bottom)
				(hide yes)
			)
		)
		(pin "1"
		)
		(instances
			(project "sodimm-ddr5-tester"
				(path ""
					(reference "#PWR0129")
					(unit 1)
				)
			)
		)
	)
	(symbol
		(lib_id "antmicroCapacitors0402:C_100n_0402")
		(at 80.645 189.23 90)
		(unit 1)
		(exclude_from_sim no)
		(in_bom yes)
		(on_board yes)
		(dnp no)
		(property "Reference" "C52"
			(at 81.28 184.785 90)
			(effects
				(font
					(size 1.27 1.27)
					(thickness 0.15)
				)
				(justify right)
			)
		)
		(property "Value" "C_100n_0402"
			(at 90.805 168.91 0)
			(effects
				(font
					(size 1.27 1.27)
					(thickness 0.15)
				)
				(justify left bottom)
				(hide yes)
			)
		)
		(property "Footprint" "antmicro-footprints:C_0402_1005Metric"
			(at 93.345 168.91 0)
			(effects
				(font
					(size 1.27 1.27)
					(thickness 0.15)
				)
				(justify left bottom)
				(hide yes)
			)
		)
		(property "Datasheet" "https://www.murata.com/products/productdetail?partno=GRM155R61H104KE14%23"
			(at 95.885 168.91 0)
			(effects
				(font
					(size 1.27 1.27)
					(thickness 0.15)
				)
				(justify left bottom)
				(hide yes)
			)
		)
		(property "Description" ""
			(at 80.645 189.23 0)
			(effects
				(font
					(size 1.27 1.27)
				)
			)
		)
		(property "MPN" "GRM155R61H104KE14D"
			(at 98.425 168.91 0)
			(effects
				(font
					(size 1.27 1.27)
					(thickness 0.15)
				)
				(justify left bottom)
				(hide yes)
			)
		)
		(property "Manufacturer" "Murata"
			(at 100.965 168.91 0)
			(effects
				(font
					(size 1.27 1.27)
					(thickness 0.15)
				)
				(justify left bottom)
				(hide yes)
			)
		)
		(property "License" "Apache-2.0"
			(at 103.505 168.91 0)
			(effects
				(font
					(size 1.27 1.27)
					(thickness 0.15)
				)
				(justify left bottom)
				(hide yes)
			)
		)
		(property "Author" "Antmicro"
			(at 106.045 168.91 0)
			(effects
				(font
					(size 1.27 1.27)
					(thickness 0.15)
				)
				(justify left bottom)
				(hide yes)
			)
		)
		(property "Val" "100n"
			(at 81.28 188.595 90)
			(effects
				(font
					(size 1.27 1.27)
					(thickness 0.15)
				)
				(justify right)
			)
		)
		(property "Voltage" "50V"
			(at 108.585 168.91 0)
			(effects
				(font
					(size 1.27 1.27)
				)
				(justify left bottom)
				(hide yes)
			)
		)
		(property "Dielectric" "X5R"
			(at 111.125 168.91 0)
			(effects
				(font
					(size 1.27 1.27)
				)
				(justify left bottom)
				(hide yes)
			)
		)
		(pin "1"
		)
		(pin "2"
		)
		(instances
			(project "sodimm-ddr5-tester"
				(path ""
					(reference "C52")
					(unit 1)
				)
			)
		)
	)
	(symbol
		(lib_id "antmicroCapacitorsmisc:C_100u_0805")
		(at 99.695 66.675 90)
		(unit 1)
		(exclude_from_sim no)
		(in_bom yes)
		(on_board yes)
		(dnp no)
		(fields_autoplaced yes)
		(property "Reference" "C54"
			(at 102.0191 63.298 90)
			(effects
				(font
					(size 1.27 1.27)
					(thickness 0.15)
				)
				(justify right)
			)
		)
		(property "Value" "C_100u_0805"
			(at 109.855 46.355 0)
			(effects
				(font
					(size 1.27 1.27)
					(thickness 0.15)
				)
				(justify left bottom)
				(hide yes)
			)
		)
		(property "Footprint" "antmicro-footprints:C_0805_2012Metric"
			(at 112.395 46.355 0)
			(effects
				(font
					(size 1.27 1.27)
					(thickness 0.15)
				)
				(justify left bottom)
				(hide yes)
			)
		)
		(property "Datasheet" "https://www.murata.com/products/productdetail?partno=GRM21BR60J107ME15%23"
			(at 114.935 46.355 0)
			(effects
				(font
					(size 1.27 1.27)
					(thickness 0.15)
				)
				(justify left bottom)
				(hide yes)
			)
		)
		(property "Description" ""
			(at 99.695 66.675 0)
			(effects
				(font
					(size 1.27 1.27)
				)
			)
		)
		(property "MPN" "GRM21BR60J107ME15L"
			(at 117.475 46.355 0)
			(effects
				(font
					(size 1.27 1.27)
					(thickness 0.15)
				)
				(justify left bottom)
				(hide yes)
			)
		)
		(property "Manufacturer" "Murata"
			(at 120.015 46.355 0)
			(effects
				(font
					(size 1.27 1.27)
					(thickness 0.15)
				)
				(justify left bottom)
				(hide yes)
			)
		)
		(property "License" "Apache-2.0"
			(at 122.555 46.355 0)
			(effects
				(font
					(size 1.27 1.27)
					(thickness 0.15)
				)
				(justify left bottom)
				(hide yes)
			)
		)
		(property "Author" "Antmicro"
			(at 125.095 46.355 0)
			(effects
				(font
					(size 1.27 1.27)
					(thickness 0.15)
				)
				(justify left bottom)
				(hide yes)
			)
		)
		(property "Val" "100u"
			(at 102.0191 65.8217 90)
			(effects
				(font
					(size 1.27 1.27)
					(thickness 0.15)
				)
				(justify right)
			)
		)
		(property "Voltage" ""
			(at 127.635 46.355 0)
			(effects
				(font
					(size 1.27 1.27)
				)
				(justify left bottom)
				(hide yes)
			)
		)
		(property "Dielectric" ""
			(at 130.175 46.355 0)
			(effects
				(font
					(size 1.27 1.27)
				)
				(justify left bottom)
				(hide yes)
			)
		)
		(pin "1"
		)
		(pin "2"
		)
		(instances
			(project "sodimm-ddr5-tester"
				(path ""
					(reference "C54")
					(unit 1)
				)
			)
		)
	)
	(symbol
		(lib_id "antmicropower:GND")
		(at 83.185 124.46 0)
		(mirror y)
		(unit 1)
		(exclude_from_sim no)
		(in_bom yes)
		(on_board yes)
		(dnp no)
		(fields_autoplaced yes)
		(property "Reference" "#PWR097"
			(at 83.185 130.81 0)
			(effects
				(font
					(size 1.27 1.27)
				)
				(hide yes)
			)
		)
		(property "Value" "GND"
			(at 85.09 125.73 0)
			(effects
				(font
					(size 1.27 1.27)
					(thickness 0.15)
				)
				(justify right)
			)
		)
		(property "Footprint" ""
			(at 74.295 132.08 0)
			(effects
				(font
					(size 1.27 1.27)
					(thickness 0.15)
				)
				(justify left bottom)
				(hide yes)
			)
		)
		(property "Datasheet" ""
			(at 74.295 137.16 0)
			(effects
				(font
					(size 1.27 1.27)
					(thickness 0.15)
				)
				(justify left bottom)
				(hide yes)
			)
		)
		(property "Description" ""
			(at 74.295 139.7 0)
			(effects
				(font
					(size 1.27 1.27)
				)
				(justify left bottom)
				(hide yes)
			)
		)
		(property "Author" "Antmicro"
			(at 74.295 132.08 0)
			(effects
				(font
					(size 1.27 1.27)
					(thickness 0.15)
				)
				(justify left bottom)
				(hide yes)
			)
		)
		(property "License" "Apache-2.0"
			(at 74.295 134.62 0)
			(effects
				(font
					(size 1.27 1.27)
					(thickness 0.15)
				)
				(justify left bottom)
				(hide yes)
			)
		)
		(pin "1"
		)
		(instances
			(project "sodimm-ddr5-tester"
				(path ""
					(reference "#PWR097")
					(unit 1)
				)
			)
		)
	)
	(symbol
		(lib_id "antmicropower:GND")
		(at 38.735 220.98 0)
		(unit 1)
		(exclude_from_sim no)
		(in_bom yes)
		(on_board yes)
		(dnp no)
		(fields_autoplaced yes)
		(property "Reference" "#PWR064"
			(at 38.735 227.33 0)
			(effects
				(font
					(size 1.27 1.27)
				)
				(hide yes)
			)
		)
		(property "Value" "GND"
			(at 40.64 222.25 0)
			(effects
				(font
					(size 1.27 1.27)
					(thickness 0.15)
				)
				(justify left)
			)
		)
		(property "Footprint" ""
			(at 47.625 228.6 0)
			(effects
				(font
					(size 1.27 1.27)
					(thickness 0.15)
				)
				(justify left bottom)
				(hide yes)
			)
		)
		(property "Datasheet" ""
			(at 47.625 233.68 0)
			(effects
				(font
					(size 1.27 1.27)
					(thickness 0.15)
				)
				(justify left bottom)
				(hide yes)
			)
		)
		(property "Description" ""
			(at 47.625 236.22 0)
			(effects
				(font
					(size 1.27 1.27)
				)
				(justify left bottom)
				(hide yes)
			)
		)
		(property "Author" "Antmicro"
			(at 47.625 228.6 0)
			(effects
				(font
					(size 1.27 1.27)
					(thickness 0.15)
				)
				(justify left bottom)
				(hide yes)
			)
		)
		(property "License" "Apache-2.0"
			(at 47.625 231.14 0)
			(effects
				(font
					(size 1.27 1.27)
					(thickness 0.15)
				)
				(justify left bottom)
				(hide yes)
			)
		)
		(pin "1"
		)
		(instances
			(project "sodimm-ddr5-tester"
				(path ""
					(reference "#PWR064")
					(unit 1)
				)
			)
		)
	)
	(symbol
		(lib_id "antmicroCapacitors0402:C_100n_0402")
		(at 59.69 189.23 90)
		(unit 1)
		(exclude_from_sim no)
		(in_bom yes)
		(on_board yes)
		(dnp no)
		(property "Reference" "C35"
			(at 60.325 184.785 90)
			(effects
				(font
					(size 1.27 1.27)
					(thickness 0.15)
				)
				(justify right)
			)
		)
		(property "Value" "C_100n_0402"
			(at 69.85 168.91 0)
			(effects
				(font
					(size 1.27 1.27)
					(thickness 0.15)
				)
				(justify left bottom)
				(hide yes)
			)
		)
		(property "Footprint" "antmicro-footprints:C_0402_1005Metric"
			(at 72.39 168.91 0)
			(effects
				(font
					(size 1.27 1.27)
					(thickness 0.15)
				)
				(justify left bottom)
				(hide yes)
			)
		)
		(property "Datasheet" "https://www.murata.com/products/productdetail?partno=GRM155R61H104KE14%23"
			(at 74.93 168.91 0)
			(effects
				(font
					(size 1.27 1.27)
					(thickness 0.15)
				)
				(justify left bottom)
				(hide yes)
			)
		)
		(property "Description" ""
			(at 59.69 189.23 0)
			(effects
				(font
					(size 1.27 1.27)
				)
			)
		)
		(property "MPN" "GRM155R61H104KE14D"
			(at 77.47 168.91 0)
			(effects
				(font
					(size 1.27 1.27)
					(thickness 0.15)
				)
				(justify left bottom)
				(hide yes)
			)
		)
		(property "Manufacturer" "Murata"
			(at 80.01 168.91 0)
			(effects
				(font
					(size 1.27 1.27)
					(thickness 0.15)
				)
				(justify left bottom)
				(hide yes)
			)
		)
		(property "License" "Apache-2.0"
			(at 82.55 168.91 0)
			(effects
				(font
					(size 1.27 1.27)
					(thickness 0.15)
				)
				(justify left bottom)
				(hide yes)
			)
		)
		(property "Author" "Antmicro"
			(at 85.09 168.91 0)
			(effects
				(font
					(size 1.27 1.27)
					(thickness 0.15)
				)
				(justify left bottom)
				(hide yes)
			)
		)
		(property "Val" "100n"
			(at 60.325 188.595 90)
			(effects
				(font
					(size 1.27 1.27)
					(thickness 0.15)
				)
				(justify right)
			)
		)
		(property "Voltage" "50V"
			(at 87.63 168.91 0)
			(effects
				(font
					(size 1.27 1.27)
				)
				(justify left bottom)
				(hide yes)
			)
		)
		(property "Dielectric" "X5R"
			(at 90.17 168.91 0)
			(effects
				(font
					(size 1.27 1.27)
				)
				(justify left bottom)
				(hide yes)
			)
		)
		(pin "1"
		)
		(pin "2"
		)
		(instances
			(project "sodimm-ddr5-tester"
				(path ""
					(reference "C35")
					(unit 1)
				)
			)
		)
	)
	(symbol
		(lib_id "antmicroCapacitorspol:C_Pol_330u_6.3V_KEMET-T520-B")
		(at 57.15 62.23 270)
		(unit 1)
		(exclude_from_sim no)
		(in_bom yes)
		(on_board yes)
		(dnp no)
		(property "Reference" "C25"
			(at 59.69 63.5 90)
			(effects
				(font
					(size 1.27 1.27)
					(thickness 0.15)
				)
				(justify left)
			)
		)
		(property "Value" "C_Pol_330u_6.3V_KEMET-T520-B"
			(at 54.61 76.2 0)
			(effects
				(font
					(size 1.27 1.27)
					(thickness 0.15)
				)
				(justify left bottom)
				(hide yes)
			)
		)
		(property "Footprint" "antmicro-footprints:C_Pol_EIA-B"
			(at 49.53 76.2 0)
			(effects
				(font
					(size 1.27 1.27)
					(thickness 0.15)
				)
				(justify left bottom)
				(hide yes)
			)
		)
		(property "Datasheet" "https://content.kemet.com/datasheets/KEM_T2076_T52X-530.pdf"
			(at 46.99 76.2 0)
			(effects
				(font
					(size 1.27 1.27)
					(thickness 0.15)
				)
				(justify left bottom)
				(hide yes)
			)
		)
		(property "Description" ""
			(at 57.15 62.23 0)
			(effects
				(font
					(size 1.27 1.27)
				)
			)
		)
		(property "Val" "330u/6.3V"
			(at 59.69 66.0237 90)
			(effects
				(font
					(size 1.27 1.27)
					(thickness 0.15)
				)
				(justify left)
			)
		)
		(property "MPN" "T520B337M006ATE040"
			(at 44.45 76.2 0)
			(effects
				(font
					(size 1.27 1.27)
					(thickness 0.15)
				)
				(justify left bottom)
				(hide yes)
			)
		)
		(property "Manufacturer" "KEMET"
			(at 41.91 76.2 0)
			(effects
				(font
					(size 1.27 1.27)
					(thickness 0.15)
				)
				(justify left bottom)
				(hide yes)
			)
		)
		(property "License" "Apache-2.0"
			(at 39.37 76.2 0)
			(effects
				(font
					(size 1.27 1.27)
					(thickness 0.15)
				)
				(justify left bottom)
				(hide yes)
			)
		)
		(property "Author" "Antmicro"
			(at 36.83 76.2 0)
			(effects
				(font
					(size 1.27 1.27)
					(thickness 0.15)
				)
				(justify left bottom)
				(hide yes)
			)
		)
		(property "Voltage" "6.3V"
			(at 34.29 76.2 0)
			(effects
				(font
					(size 1.27 1.27)
				)
				(justify left bottom)
				(hide yes)
			)
		)
		(pin "1"
		)
		(pin "2"
		)
		(instances
			(project "sodimm-ddr5-tester"
				(path ""
					(reference "C25")
					(unit 1)
				)
			)
		)
	)
	(symbol
		(lib_id "antmicroCapacitors0402:C_100n_0402")
		(at 66.675 219.71 90)
		(unit 1)
		(exclude_from_sim no)
		(in_bom yes)
		(on_board yes)
		(dnp no)
		(property "Reference" "C41"
			(at 67.31 215.265 90)
			(effects
				(font
					(size 1.27 1.27)
					(thickness 0.15)
				)
				(justify right)
			)
		)
		(property "Value" "C_100n_0402"
			(at 76.835 199.39 0)
			(effects
				(font
					(size 1.27 1.27)
					(thickness 0.15)
				)
				(justify left bottom)
				(hide yes)
			)
		)
		(property "Footprint" "antmicro-footprints:C_0402_1005Metric"
			(at 79.375 199.39 0)
			(effects
				(font
					(size 1.27 1.27)
					(thickness 0.15)
				)
				(justify left bottom)
				(hide yes)
			)
		)
		(property "Datasheet" "https://www.murata.com/products/productdetail?partno=GRM155R61H104KE14%23"
			(at 81.915 199.39 0)
			(effects
				(font
					(size 1.27 1.27)
					(thickness 0.15)
				)
				(justify left bottom)
				(hide yes)
			)
		)
		(property "Description" ""
			(at 66.675 219.71 0)
			(effects
				(font
					(size 1.27 1.27)
				)
			)
		)
		(property "MPN" "GRM155R61H104KE14D"
			(at 84.455 199.39 0)
			(effects
				(font
					(size 1.27 1.27)
					(thickness 0.15)
				)
				(justify left bottom)
				(hide yes)
			)
		)
		(property "Manufacturer" "Murata"
			(at 86.995 199.39 0)
			(effects
				(font
					(size 1.27 1.27)
					(thickness 0.15)
				)
				(justify left bottom)
				(hide yes)
			)
		)
		(property "License" "Apache-2.0"
			(at 89.535 199.39 0)
			(effects
				(font
					(size 1.27 1.27)
					(thickness 0.15)
				)
				(justify left bottom)
				(hide yes)
			)
		)
		(property "Author" "Antmicro"
			(at 92.075 199.39 0)
			(effects
				(font
					(size 1.27 1.27)
					(thickness 0.15)
				)
				(justify left bottom)
				(hide yes)
			)
		)
		(property "Val" "100n"
			(at 67.31 219.075 90)
			(effects
				(font
					(size 1.27 1.27)
					(thickness 0.15)
				)
				(justify right)
			)
		)
		(property "Voltage" "50V"
			(at 94.615 199.39 0)
			(effects
				(font
					(size 1.27 1.27)
				)
				(justify left bottom)
				(hide yes)
			)
		)
		(property "Dielectric" "X5R"
			(at 97.155 199.39 0)
			(effects
				(font
					(size 1.27 1.27)
				)
				(justify left bottom)
				(hide yes)
			)
		)
		(pin "1"
		)
		(pin "2"
		)
		(instances
			(project "sodimm-ddr5-tester"
				(path ""
					(reference "C41")
					(unit 1)
				)
			)
		)
	)
	(symbol
		(lib_id "antmicropower:GND")
		(at 364.49 63.5 0)
		(unit 1)
		(exclude_from_sim no)
		(in_bom yes)
		(on_board yes)
		(dnp no)
		(fields_autoplaced yes)
		(property "Reference" "#PWR0157"
			(at 364.49 69.85 0)
			(effects
				(font
					(size 1.27 1.27)
				)
				(hide yes)
			)
		)
		(property "Value" "GND"
			(at 367.03 64.77 0)
			(effects
				(font
					(size 1.27 1.27)
					(thickness 0.15)
				)
				(justify left)
			)
		)
		(property "Footprint" ""
			(at 373.38 71.12 0)
			(effects
				(font
					(size 1.27 1.27)
					(thickness 0.15)
				)
				(justify left bottom)
				(hide yes)
			)
		)
		(property "Datasheet" ""
			(at 373.38 76.2 0)
			(effects
				(font
					(size 1.27 1.27)
					(thickness 0.15)
				)
				(justify left bottom)
				(hide yes)
			)
		)
		(property "Description" ""
			(at 373.38 78.74 0)
			(effects
				(font
					(size 1.27 1.27)
				)
				(justify left bottom)
				(hide yes)
			)
		)
		(property "Author" "Antmicro"
			(at 373.38 71.12 0)
			(effects
				(font
					(size 1.27 1.27)
					(thickness 0.15)
				)
				(justify left bottom)
				(hide yes)
			)
		)
		(property "License" "Apache-2.0"
			(at 373.38 73.66 0)
			(effects
				(font
					(size 1.27 1.27)
					(thickness 0.15)
				)
				(justify left bottom)
				(hide yes)
			)
		)
		(pin "1"
		)
		(instances
			(project "sodimm-ddr5-tester"
				(path ""
					(reference "#PWR0157")
					(unit 1)
				)
			)
		)
	)
	(symbol
		(lib_id "antmicropower:GND")
		(at 330.835 95.885 0)
		(unit 1)
		(exclude_from_sim no)
		(in_bom yes)
		(on_board yes)
		(dnp no)
		(fields_autoplaced yes)
		(property "Reference" "#PWR0147"
			(at 330.835 102.235 0)
			(effects
				(font
					(size 1.27 1.27)
				)
				(hide yes)
			)
		)
		(property "Value" "GND"
			(at 332.74 97.155 0)
			(effects
				(font
					(size 1.27 1.27)
					(thickness 0.15)
				)
				(justify left)
			)
		)
		(property "Footprint" ""
			(at 339.725 103.505 0)
			(effects
				(font
					(size 1.27 1.27)
					(thickness 0.15)
				)
				(justify left bottom)
				(hide yes)
			)
		)
		(property "Datasheet" ""
			(at 339.725 108.585 0)
			(effects
				(font
					(size 1.27 1.27)
					(thickness 0.15)
				)
				(justify left bottom)
				(hide yes)
			)
		)
		(property "Description" ""
			(at 339.725 111.125 0)
			(effects
				(font
					(size 1.27 1.27)
				)
				(justify left bottom)
				(hide yes)
			)
		)
		(property "Author" "Antmicro"
			(at 339.725 103.505 0)
			(effects
				(font
					(size 1.27 1.27)
					(thickness 0.15)
				)
				(justify left bottom)
				(hide yes)
			)
		)
		(property "License" "Apache-2.0"
			(at 339.725 106.045 0)
			(effects
				(font
					(size 1.27 1.27)
					(thickness 0.15)
				)
				(justify left bottom)
				(hide yes)
			)
		)
		(pin "1"
		)
		(instances
			(project "sodimm-ddr5-tester"
				(path ""
					(reference "#PWR0147")
					(unit 1)
				)
			)
		)
	)
	(symbol
		(lib_id "antmicropower:GND")
		(at 337.185 127 0)
		(unit 1)
		(exclude_from_sim no)
		(in_bom yes)
		(on_board yes)
		(dnp no)
		(fields_autoplaced yes)
		(property "Reference" "#PWR0163"
			(at 337.185 133.35 0)
			(effects
				(font
					(size 1.27 1.27)
				)
				(hide yes)
			)
		)
		(property "Value" "GND"
			(at 339.09 128.27 0)
			(effects
				(font
					(size 1.27 1.27)
					(thickness 0.15)
				)
				(justify left)
			)
		)
		(property "Footprint" ""
			(at 346.075 134.62 0)
			(effects
				(font
					(size 1.27 1.27)
					(thickness 0.15)
				)
				(justify left bottom)
				(hide yes)
			)
		)
		(property "Datasheet" ""
			(at 346.075 139.7 0)
			(effects
				(font
					(size 1.27 1.27)
					(thickness 0.15)
				)
				(justify left bottom)
				(hide yes)
			)
		)
		(property "Description" ""
			(at 346.075 142.24 0)
			(effects
				(font
					(size 1.27 1.27)
				)
				(justify left bottom)
				(hide yes)
			)
		)
		(property "Author" "Antmicro"
			(at 346.075 134.62 0)
			(effects
				(font
					(size 1.27 1.27)
					(thickness 0.15)
				)
				(justify left bottom)
				(hide yes)
			)
		)
		(property "License" "Apache-2.0"
			(at 346.075 137.16 0)
			(effects
				(font
					(size 1.27 1.27)
					(thickness 0.15)
				)
				(justify left bottom)
				(hide yes)
			)
		)
		(pin "1"
		)
		(instances
			(project "sodimm-ddr5-tester"
				(path ""
					(reference "#PWR0163")
					(unit 1)
				)
			)
		)
	)
	(symbol
		(lib_id "antmicroCapacitors0402:C_100n_0402")
		(at 87.63 189.23 90)
		(unit 1)
		(exclude_from_sim no)
		(in_bom yes)
		(on_board yes)
		(dnp no)
		(property "Reference" "C58"
			(at 88.265 184.785 90)
			(effects
				(font
					(size 1.27 1.27)
					(thickness 0.15)
				)
				(justify right)
			)
		)
		(property "Value" "C_100n_0402"
			(at 97.79 168.91 0)
			(effects
				(font
					(size 1.27 1.27)
					(thickness 0.15)
				)
				(justify left bottom)
				(hide yes)
			)
		)
		(property "Footprint" "antmicro-footprints:C_0402_1005Metric"
			(at 100.33 168.91 0)
			(effects
				(font
					(size 1.27 1.27)
					(thickness 0.15)
				)
				(justify left bottom)
				(hide yes)
			)
		)
		(property "Datasheet" "https://www.murata.com/products/productdetail?partno=GRM155R61H104KE14%23"
			(at 102.87 168.91 0)
			(effects
				(font
					(size 1.27 1.27)
					(thickness 0.15)
				)
				(justify left bottom)
				(hide yes)
			)
		)
		(property "Description" ""
			(at 87.63 189.23 0)
			(effects
				(font
					(size 1.27 1.27)
				)
			)
		)
		(property "MPN" "GRM155R61H104KE14D"
			(at 105.41 168.91 0)
			(effects
				(font
					(size 1.27 1.27)
					(thickness 0.15)
				)
				(justify left bottom)
				(hide yes)
			)
		)
		(property "Manufacturer" "Murata"
			(at 107.95 168.91 0)
			(effects
				(font
					(size 1.27 1.27)
					(thickness 0.15)
				)
				(justify left bottom)
				(hide yes)
			)
		)
		(property "License" "Apache-2.0"
			(at 110.49 168.91 0)
			(effects
				(font
					(size 1.27 1.27)
					(thickness 0.15)
				)
				(justify left bottom)
				(hide yes)
			)
		)
		(property "Author" "Antmicro"
			(at 113.03 168.91 0)
			(effects
				(font
					(size 1.27 1.27)
					(thickness 0.15)
				)
				(justify left bottom)
				(hide yes)
			)
		)
		(property "Val" "100n"
			(at 88.265 188.595 90)
			(effects
				(font
					(size 1.27 1.27)
					(thickness 0.15)
				)
				(justify right)
			)
		)
		(property "Voltage" "50V"
			(at 115.57 168.91 0)
			(effects
				(font
					(size 1.27 1.27)
				)
				(justify left bottom)
				(hide yes)
			)
		)
		(property "Dielectric" "X5R"
			(at 118.11 168.91 0)
			(effects
				(font
					(size 1.27 1.27)
				)
				(justify left bottom)
				(hide yes)
			)
		)
		(pin "1"
		)
		(pin "2"
		)
		(instances
			(project "sodimm-ddr5-tester"
				(path ""
					(reference "C58")
					(unit 1)
				)
			)
		)
	)
	(symbol
		(lib_id "antmicropower:GND")
		(at 39.37 94.615 0)
		(unit 1)
		(exclude_from_sim no)
		(in_bom yes)
		(on_board yes)
		(dnp no)
		(fields_autoplaced yes)
		(property "Reference" "#PWR056"
			(at 39.37 100.965 0)
			(effects
				(font
					(size 1.27 1.27)
				)
				(hide yes)
			)
		)
		(property "Value" "GND"
			(at 41.91 95.885 0)
			(effects
				(font
					(size 1.27 1.27)
					(thickness 0.15)
				)
				(justify left)
			)
		)
		(property "Footprint" ""
			(at 48.26 102.235 0)
			(effects
				(font
					(size 1.27 1.27)
					(thickness 0.15)
				)
				(justify left bottom)
				(hide yes)
			)
		)
		(property "Datasheet" ""
			(at 48.26 107.315 0)
			(effects
				(font
					(size 1.27 1.27)
					(thickness 0.15)
				)
				(justify left bottom)
				(hide yes)
			)
		)
		(property "Description" ""
			(at 48.26 109.855 0)
			(effects
				(font
					(size 1.27 1.27)
				)
				(justify left bottom)
				(hide yes)
			)
		)
		(property "Author" "Antmicro"
			(at 48.26 102.235 0)
			(effects
				(font
					(size 1.27 1.27)
					(thickness 0.15)
				)
				(justify left bottom)
				(hide yes)
			)
		)
		(property "License" "Apache-2.0"
			(at 48.26 104.775 0)
			(effects
				(font
					(size 1.27 1.27)
					(thickness 0.15)
				)
				(justify left bottom)
				(hide yes)
			)
		)
		(pin "1"
		)
		(instances
			(project "sodimm-ddr5-tester"
				(path ""
					(reference "#PWR056")
					(unit 1)
				)
			)
		)
	)
	(symbol
		(lib_id "antmicroCapacitors0402:C_100n_0402")
		(at 80.645 219.71 90)
		(unit 1)
		(exclude_from_sim no)
		(in_bom yes)
		(on_board yes)
		(dnp no)
		(property "Reference" "C53"
			(at 81.28 215.265 90)
			(effects
				(font
					(size 1.27 1.27)
					(thickness 0.15)
				)
				(justify right)
			)
		)
		(property "Value" "C_100n_0402"
			(at 90.805 199.39 0)
			(effects
				(font
					(size 1.27 1.27)
					(thickness 0.15)
				)
				(justify left bottom)
				(hide yes)
			)
		)
		(property "Footprint" "antmicro-footprints:C_0402_1005Metric"
			(at 93.345 199.39 0)
			(effects
				(font
					(size 1.27 1.27)
					(thickness 0.15)
				)
				(justify left bottom)
				(hide yes)
			)
		)
		(property "Datasheet" "https://www.murata.com/products/productdetail?partno=GRM155R61H104KE14%23"
			(at 95.885 199.39 0)
			(effects
				(font
					(size 1.27 1.27)
					(thickness 0.15)
				)
				(justify left bottom)
				(hide yes)
			)
		)
		(property "Description" ""
			(at 80.645 219.71 0)
			(effects
				(font
					(size 1.27 1.27)
				)
			)
		)
		(property "MPN" "GRM155R61H104KE14D"
			(at 98.425 199.39 0)
			(effects
				(font
					(size 1.27 1.27)
					(thickness 0.15)
				)
				(justify left bottom)
				(hide yes)
			)
		)
		(property "Manufacturer" "Murata"
			(at 100.965 199.39 0)
			(effects
				(font
					(size 1.27 1.27)
					(thickness 0.15)
				)
				(justify left bottom)
				(hide yes)
			)
		)
		(property "License" "Apache-2.0"
			(at 103.505 199.39 0)
			(effects
				(font
					(size 1.27 1.27)
					(thickness 0.15)
				)
				(justify left bottom)
				(hide yes)
			)
		)
		(property "Author" "Antmicro"
			(at 106.045 199.39 0)
			(effects
				(font
					(size 1.27 1.27)
					(thickness 0.15)
				)
				(justify left bottom)
				(hide yes)
			)
		)
		(property "Val" "100n"
			(at 81.28 219.075 90)
			(effects
				(font
					(size 1.27 1.27)
					(thickness 0.15)
				)
				(justify right)
			)
		)
		(property "Voltage" "50V"
			(at 108.585 199.39 0)
			(effects
				(font
					(size 1.27 1.27)
				)
				(justify left bottom)
				(hide yes)
			)
		)
		(property "Dielectric" "X5R"
			(at 111.125 199.39 0)
			(effects
				(font
					(size 1.27 1.27)
				)
				(justify left bottom)
				(hide yes)
			)
		)
		(pin "1"
		)
		(pin "2"
		)
		(instances
			(project "sodimm-ddr5-tester"
				(path ""
					(reference "C53")
					(unit 1)
				)
			)
		)
	)
	(symbol
		(lib_id "antmicroCapacitors0402:C_100n_0402")
		(at 123.19 160.655 90)
		(unit 1)
		(exclude_from_sim no)
		(in_bom yes)
		(on_board yes)
		(dnp no)
		(property "Reference" "C20"
			(at 127.635 156.21 90)
			(effects
				(font
					(size 1.27 1.27)
					(thickness 0.15)
				)
				(justify left)
			)
		)
		(property "Value" "C_100n_0402"
			(at 133.35 140.335 0)
			(effects
				(font
					(size 1.27 1.27)
					(thickness 0.15)
				)
				(justify left bottom)
				(hide yes)
			)
		)
		(property "Footprint" "antmicro-footprints:C_0402_1005Metric"
			(at 135.89 140.335 0)
			(effects
				(font
					(size 1.27 1.27)
					(thickness 0.15)
				)
				(justify left bottom)
				(hide yes)
			)
		)
		(property "Datasheet" "https://www.murata.com/products/productdetail?partno=GRM155R61H104KE14%23"
			(at 138.43 140.335 0)
			(effects
				(font
					(size 1.27 1.27)
					(thickness 0.15)
				)
				(justify left bottom)
				(hide yes)
			)
		)
		(property "Description" ""
			(at 123.19 160.655 0)
			(effects
				(font
					(size 1.27 1.27)
				)
			)
		)
		(property "MPN" "GRM155R61H104KE14D"
			(at 140.97 140.335 0)
			(effects
				(font
					(size 1.27 1.27)
					(thickness 0.15)
				)
				(justify left bottom)
				(hide yes)
			)
		)
		(property "Manufacturer" "Murata"
			(at 143.51 140.335 0)
			(effects
				(font
					(size 1.27 1.27)
					(thickness 0.15)
				)
				(justify left bottom)
				(hide yes)
			)
		)
		(property "License" "Apache-2.0"
			(at 146.05 140.335 0)
			(effects
				(font
					(size 1.27 1.27)
					(thickness 0.15)
				)
				(justify left bottom)
				(hide yes)
			)
		)
		(property "Author" "Antmicro"
			(at 148.59 140.335 0)
			(effects
				(font
					(size 1.27 1.27)
					(thickness 0.15)
				)
				(justify left bottom)
				(hide yes)
			)
		)
		(property "Val" "100n"
			(at 128.905 160.02 90)
			(effects
				(font
					(size 1.27 1.27)
					(thickness 0.15)
				)
				(justify left)
			)
		)
		(property "Voltage" "50V"
			(at 151.13 140.335 0)
			(effects
				(font
					(size 1.27 1.27)
				)
				(justify left bottom)
				(hide yes)
			)
		)
		(property "Dielectric" "X5R"
			(at 153.67 140.335 0)
			(effects
				(font
					(size 1.27 1.27)
				)
				(justify left bottom)
				(hide yes)
			)
		)
		(pin "1"
		)
		(pin "2"
		)
		(instances
			(project "sodimm-ddr5-tester"
				(path ""
					(reference "C20")
					(unit 1)
				)
			)
		)
	)
	(symbol
		(lib_id "antmicroCapacitors0402:C_100n_0402")
		(at 45.085 247.65 90)
		(unit 1)
		(exclude_from_sim no)
		(in_bom yes)
		(on_board yes)
		(dnp no)
		(property "Reference" "C21"
			(at 49.53 243.205 90)
			(effects
				(font
					(size 1.27 1.27)
					(thickness 0.15)
				)
				(justify left)
			)
		)
		(property "Value" "C_100n_0402"
			(at 55.245 227.33 0)
			(effects
				(font
					(size 1.27 1.27)
					(thickness 0.15)
				)
				(justify left bottom)
				(hide yes)
			)
		)
		(property "Footprint" "antmicro-footprints:C_0402_1005Metric"
			(at 57.785 227.33 0)
			(effects
				(font
					(size 1.27 1.27)
					(thickness 0.15)
				)
				(justify left bottom)
				(hide yes)
			)
		)
		(property "Datasheet" "https://www.murata.com/products/productdetail?partno=GRM155R61H104KE14%23"
			(at 60.325 227.33 0)
			(effects
				(font
					(size 1.27 1.27)
					(thickness 0.15)
				)
				(justify left bottom)
				(hide yes)
			)
		)
		(property "Description" ""
			(at 45.085 247.65 0)
			(effects
				(font
					(size 1.27 1.27)
				)
			)
		)
		(property "MPN" "GRM155R61H104KE14D"
			(at 62.865 227.33 0)
			(effects
				(font
					(size 1.27 1.27)
					(thickness 0.15)
				)
				(justify left bottom)
				(hide yes)
			)
		)
		(property "Manufacturer" "Murata"
			(at 65.405 227.33 0)
			(effects
				(font
					(size 1.27 1.27)
					(thickness 0.15)
				)
				(justify left bottom)
				(hide yes)
			)
		)
		(property "License" "Apache-2.0"
			(at 67.945 227.33 0)
			(effects
				(font
					(size 1.27 1.27)
					(thickness 0.15)
				)
				(justify left bottom)
				(hide yes)
			)
		)
		(property "Author" "Antmicro"
			(at 70.485 227.33 0)
			(effects
				(font
					(size 1.27 1.27)
					(thickness 0.15)
				)
				(justify left bottom)
				(hide yes)
			)
		)
		(property "Val" "100n"
			(at 50.8 247.015 90)
			(effects
				(font
					(size 1.27 1.27)
					(thickness 0.15)
				)
				(justify left)
			)
		)
		(property "Voltage" "50V"
			(at 73.025 227.33 0)
			(effects
				(font
					(size 1.27 1.27)
				)
				(justify left bottom)
				(hide yes)
			)
		)
		(property "Dielectric" "X5R"
			(at 75.565 227.33 0)
			(effects
				(font
					(size 1.27 1.27)
				)
				(justify left bottom)
				(hide yes)
			)
		)
		(pin "1"
		)
		(pin "2"
		)
		(instances
			(project "sodimm-ddr5-tester"
				(path ""
					(reference "C21")
					(unit 1)
				)
			)
		)
	)
	(symbol
		(lib_id "antmicropower:GND")
		(at 66.675 220.98 0)
		(unit 1)
		(exclude_from_sim no)
		(in_bom yes)
		(on_board yes)
		(dnp no)
		(fields_autoplaced yes)
		(property "Reference" "#PWR088"
			(at 66.675 227.33 0)
			(effects
				(font
					(size 1.27 1.27)
				)
				(hide yes)
			)
		)
		(property "Value" "GND"
			(at 68.58 222.25 0)
			(effects
				(font
					(size 1.27 1.27)
					(thickness 0.15)
				)
				(justify left)
			)
		)
		(property "Footprint" ""
			(at 75.565 228.6 0)
			(effects
				(font
					(size 1.27 1.27)
					(thickness 0.15)
				)
				(justify left bottom)
				(hide yes)
			)
		)
		(property "Datasheet" ""
			(at 75.565 233.68 0)
			(effects
				(font
					(size 1.27 1.27)
					(thickness 0.15)
				)
				(justify left bottom)
				(hide yes)
			)
		)
		(property "Description" ""
			(at 75.565 236.22 0)
			(effects
				(font
					(size 1.27 1.27)
				)
				(justify left bottom)
				(hide yes)
			)
		)
		(property "Author" "Antmicro"
			(at 75.565 228.6 0)
			(effects
				(font
					(size 1.27 1.27)
					(thickness 0.15)
				)
				(justify left bottom)
				(hide yes)
			)
		)
		(property "License" "Apache-2.0"
			(at 75.565 231.14 0)
			(effects
				(font
					(size 1.27 1.27)
					(thickness 0.15)
				)
				(justify left bottom)
				(hide yes)
			)
		)
		(pin "1"
		)
		(instances
			(project "sodimm-ddr5-tester"
				(path ""
					(reference "#PWR088")
					(unit 1)
				)
			)
		)
	)
	(symbol
		(lib_id "antmicropower:GND")
		(at 330.2 127 0)
		(unit 1)
		(exclude_from_sim no)
		(in_bom yes)
		(on_board yes)
		(dnp no)
		(fields_autoplaced yes)
		(property "Reference" "#PWR0161"
			(at 330.2 133.35 0)
			(effects
				(font
					(size 1.27 1.27)
				)
				(hide yes)
			)
		)
		(property "Value" "GND"
			(at 332.74 128.27 0)
			(effects
				(font
					(size 1.27 1.27)
					(thickness 0.15)
				)
				(justify left)
			)
		)
		(property "Footprint" ""
			(at 339.09 134.62 0)
			(effects
				(font
					(size 1.27 1.27)
					(thickness 0.15)
				)
				(justify left bottom)
				(hide yes)
			)
		)
		(property "Datasheet" ""
			(at 339.09 139.7 0)
			(effects
				(font
					(size 1.27 1.27)
					(thickness 0.15)
				)
				(justify left bottom)
				(hide yes)
			)
		)
		(property "Description" ""
			(at 339.09 142.24 0)
			(effects
				(font
					(size 1.27 1.27)
				)
				(justify left bottom)
				(hide yes)
			)
		)
		(property "Author" "Antmicro"
			(at 339.09 134.62 0)
			(effects
				(font
					(size 1.27 1.27)
					(thickness 0.15)
				)
				(justify left bottom)
				(hide yes)
			)
		)
		(property "License" "Apache-2.0"
			(at 339.09 137.16 0)
			(effects
				(font
					(size 1.27 1.27)
					(thickness 0.15)
				)
				(justify left bottom)
				(hide yes)
			)
		)
		(pin "1"
		)
		(instances
			(project "sodimm-ddr5-tester"
				(path ""
					(reference "#PWR0161")
					(unit 1)
				)
			)
		)
	)
	(symbol
		(lib_id "antmicroCapacitors0402:C_100n_0402")
		(at 136.525 220.345 90)
		(unit 1)
		(exclude_from_sim no)
		(in_bom yes)
		(on_board yes)
		(dnp no)
		(property "Reference" "C91"
			(at 137.16 215.9 90)
			(effects
				(font
					(size 1.27 1.27)
					(thickness 0.15)
				)
				(justify right)
			)
		)
		(property "Value" "C_100n_0402"
			(at 146.685 200.025 0)
			(effects
				(font
					(size 1.27 1.27)
					(thickness 0.15)
				)
				(justify left bottom)
				(hide yes)
			)
		)
		(property "Footprint" "antmicro-footprints:C_0402_1005Metric"
			(at 149.225 200.025 0)
			(effects
				(font
					(size 1.27 1.27)
					(thickness 0.15)
				)
				(justify left bottom)
				(hide yes)
			)
		)
		(property "Datasheet" "https://www.murata.com/products/productdetail?partno=GRM155R61H104KE14%23"
			(at 151.765 200.025 0)
			(effects
				(font
					(size 1.27 1.27)
					(thickness 0.15)
				)
				(justify left bottom)
				(hide yes)
			)
		)
		(property "Description" ""
			(at 136.525 220.345 0)
			(effects
				(font
					(size 1.27 1.27)
				)
			)
		)
		(property "MPN" "GRM155R61H104KE14D"
			(at 154.305 200.025 0)
			(effects
				(font
					(size 1.27 1.27)
					(thickness 0.15)
				)
				(justify left bottom)
				(hide yes)
			)
		)
		(property "Manufacturer" "Murata"
			(at 156.845 200.025 0)
			(effects
				(font
					(size 1.27 1.27)
					(thickness 0.15)
				)
				(justify left bottom)
				(hide yes)
			)
		)
		(property "License" "Apache-2.0"
			(at 159.385 200.025 0)
			(effects
				(font
					(size 1.27 1.27)
					(thickness 0.15)
				)
				(justify left bottom)
				(hide yes)
			)
		)
		(property "Author" "Antmicro"
			(at 161.925 200.025 0)
			(effects
				(font
					(size 1.27 1.27)
					(thickness 0.15)
				)
				(justify left bottom)
				(hide yes)
			)
		)
		(property "Val" "100n"
			(at 137.16 219.71 90)
			(effects
				(font
					(size 1.27 1.27)
					(thickness 0.15)
				)
				(justify right)
			)
		)
		(property "Voltage" "50V"
			(at 164.465 200.025 0)
			(effects
				(font
					(size 1.27 1.27)
				)
				(justify left bottom)
				(hide yes)
			)
		)
		(property "Dielectric" "X5R"
			(at 167.005 200.025 0)
			(effects
				(font
					(size 1.27 1.27)
				)
				(justify left bottom)
				(hide yes)
			)
		)
		(pin "1"
		)
		(pin "2"
		)
		(instances
			(project "sodimm-ddr5-tester"
				(path ""
					(reference "C91")
					(unit 1)
				)
			)
		)
	)
	(symbol
		(lib_id "antmicroCapacitors0402:C_100n_0402")
		(at 47.625 93.345 90)
		(unit 1)
		(exclude_from_sim no)
		(in_bom yes)
		(on_board yes)
		(dnp no)
		(property "Reference" "C19"
			(at 48.26 88.9 90)
			(effects
				(font
					(size 1.27 1.27)
					(thickness 0.15)
				)
				(justify right)
			)
		)
		(property "Value" "C_100n_0402"
			(at 57.785 73.025 0)
			(effects
				(font
					(size 1.27 1.27)
					(thickness 0.15)
				)
				(justify left bottom)
				(hide yes)
			)
		)
		(property "Footprint" "antmicro-footprints:C_0402_1005Metric"
			(at 60.325 73.025 0)
			(effects
				(font
					(size 1.27 1.27)
					(thickness 0.15)
				)
				(justify left bottom)
				(hide yes)
			)
		)
		(property "Datasheet" "https://www.murata.com/products/productdetail?partno=GRM155R61H104KE14%23"
			(at 62.865 73.025 0)
			(effects
				(font
					(size 1.27 1.27)
					(thickness 0.15)
				)
				(justify left bottom)
				(hide yes)
			)
		)
		(property "Description" ""
			(at 47.625 93.345 0)
			(effects
				(font
					(size 1.27 1.27)
				)
			)
		)
		(property "MPN" "GRM155R61H104KE14D"
			(at 65.405 73.025 0)
			(effects
				(font
					(size 1.27 1.27)
					(thickness 0.15)
				)
				(justify left bottom)
				(hide yes)
			)
		)
		(property "Manufacturer" "Murata"
			(at 67.945 73.025 0)
			(effects
				(font
					(size 1.27 1.27)
					(thickness 0.15)
				)
				(justify left bottom)
				(hide yes)
			)
		)
		(property "License" "Apache-2.0"
			(at 70.485 73.025 0)
			(effects
				(font
					(size 1.27 1.27)
					(thickness 0.15)
				)
				(justify left bottom)
				(hide yes)
			)
		)
		(property "Author" "Antmicro"
			(at 73.025 73.025 0)
			(effects
				(font
					(size 1.27 1.27)
					(thickness 0.15)
				)
				(justify left bottom)
				(hide yes)
			)
		)
		(property "Val" "100n"
			(at 48.26 92.71 90)
			(effects
				(font
					(size 1.27 1.27)
					(thickness 0.15)
				)
				(justify right)
			)
		)
		(property "Voltage" "50V"
			(at 75.565 73.025 0)
			(effects
				(font
					(size 1.27 1.27)
				)
				(justify left bottom)
				(hide yes)
			)
		)
		(property "Dielectric" "X5R"
			(at 78.105 73.025 0)
			(effects
				(font
					(size 1.27 1.27)
				)
				(justify left bottom)
				(hide yes)
			)
		)
		(pin "1"
		)
		(pin "2"
		)
		(instances
			(project "sodimm-ddr5-tester"
				(path ""
					(reference "C19")
					(unit 1)
				)
			)
		)
	)
	(symbol
		(lib_id "antmicropower:+1V0")
		(at 39.37 83.185 0)
		(unit 1)
		(exclude_from_sim no)
		(in_bom yes)
		(on_board yes)
		(dnp no)
		(fields_autoplaced yes)
		(property "Reference" "#PWR055"
			(at 39.37 86.995 0)
			(effects
				(font
					(size 1.27 1.27)
				)
				(hide yes)
			)
		)
		(property "Value" "+1V0"
			(at 39.37 79.629 0)
			(effects
				(font
					(size 1.27 1.27)
				)
			)
		)
		(property "Footprint" ""
			(at 39.37 83.185 0)
			(effects
				(font
					(size 1.27 1.27)
				)
				(hide yes)
			)
		)
		(property "Datasheet" ""
			(at 39.37 83.185 0)
			(effects
				(font
					(size 1.27 1.27)
				)
				(hide yes)
			)
		)
		(property "Description" ""
			(at 39.37 83.185 0)
			(effects
				(font
					(size 1.27 1.27)
				)
			)
		)
		(pin "1"
		)
		(instances
			(project "sodimm-ddr5-tester"
				(path ""
					(reference "#PWR055")
					(unit 1)
				)
			)
		)
	)
	(symbol
		(lib_id "antmicropower:GND")
		(at 55.88 124.46 0)
		(mirror y)
		(unit 1)
		(exclude_from_sim no)
		(in_bom yes)
		(on_board yes)
		(dnp no)
		(fields_autoplaced yes)
		(property "Reference" "#PWR074"
			(at 55.88 130.81 0)
			(effects
				(font
					(size 1.27 1.27)
				)
				(hide yes)
			)
		)
		(property "Value" "GND"
			(at 58.42 125.73 0)
			(effects
				(font
					(size 1.27 1.27)
					(thickness 0.15)
				)
				(justify right)
			)
		)
		(property "Footprint" ""
			(at 46.99 132.08 0)
			(effects
				(font
					(size 1.27 1.27)
					(thickness 0.15)
				)
				(justify left bottom)
				(hide yes)
			)
		)
		(property "Datasheet" ""
			(at 46.99 137.16 0)
			(effects
				(font
					(size 1.27 1.27)
					(thickness 0.15)
				)
				(justify left bottom)
				(hide yes)
			)
		)
		(property "Description" ""
			(at 46.99 139.7 0)
			(effects
				(font
					(size 1.27 1.27)
				)
				(justify left bottom)
				(hide yes)
			)
		)
		(property "Author" "Antmicro"
			(at 46.99 132.08 0)
			(effects
				(font
					(size 1.27 1.27)
					(thickness 0.15)
				)
				(justify left bottom)
				(hide yes)
			)
		)
		(property "License" "Apache-2.0"
			(at 46.99 134.62 0)
			(effects
				(font
					(size 1.27 1.27)
					(thickness 0.15)
				)
				(justify left bottom)
				(hide yes)
			)
		)
		(pin "1"
		)
		(instances
			(project "sodimm-ddr5-tester"
				(path ""
					(reference "#PWR074")
					(unit 1)
				)
			)
		)
	)
	(symbol
		(lib_id "antmicroCapacitors0402:C_100n_0402")
		(at 125.095 122.555 90)
		(unit 1)
		(exclude_from_sim no)
		(in_bom yes)
		(on_board yes)
		(dnp no)
		(property "Reference" "C77"
			(at 125.73 118.11 90)
			(effects
				(font
					(size 1.27 1.27)
					(thickness 0.15)
				)
				(justify right)
			)
		)
		(property "Value" "C_100n_0402"
			(at 135.255 102.235 0)
			(effects
				(font
					(size 1.27 1.27)
					(thickness 0.15)
				)
				(justify left bottom)
				(hide yes)
			)
		)
		(property "Footprint" "antmicro-footprints:C_0402_1005Metric"
			(at 137.795 102.235 0)
			(effects
				(font
					(size 1.27 1.27)
					(thickness 0.15)
				)
				(justify left bottom)
				(hide yes)
			)
		)
		(property "Datasheet" "https://www.murata.com/products/productdetail?partno=GRM155R61H104KE14%23"
			(at 140.335 102.235 0)
			(effects
				(font
					(size 1.27 1.27)
					(thickness 0.15)
				)
				(justify left bottom)
				(hide yes)
			)
		)
		(property "Description" ""
			(at 125.095 122.555 0)
			(effects
				(font
					(size 1.27 1.27)
				)
			)
		)
		(property "MPN" "GRM155R61H104KE14D"
			(at 142.875 102.235 0)
			(effects
				(font
					(size 1.27 1.27)
					(thickness 0.15)
				)
				(justify left bottom)
				(hide yes)
			)
		)
		(property "Manufacturer" "Murata"
			(at 145.415 102.235 0)
			(effects
				(font
					(size 1.27 1.27)
					(thickness 0.15)
				)
				(justify left bottom)
				(hide yes)
			)
		)
		(property "License" "Apache-2.0"
			(at 147.955 102.235 0)
			(effects
				(font
					(size 1.27 1.27)
					(thickness 0.15)
				)
				(justify left bottom)
				(hide yes)
			)
		)
		(property "Author" "Antmicro"
			(at 150.495 102.235 0)
			(effects
				(font
					(size 1.27 1.27)
					(thickness 0.15)
				)
				(justify left bottom)
				(hide yes)
			)
		)
		(property "Val" "100n"
			(at 125.73 121.92 90)
			(effects
				(font
					(size 1.27 1.27)
					(thickness 0.15)
				)
				(justify right)
			)
		)
		(property "Voltage" "50V"
			(at 153.035 102.235 0)
			(effects
				(font
					(size 1.27 1.27)
				)
				(justify left bottom)
				(hide yes)
			)
		)
		(property "Dielectric" "X5R"
			(at 155.575 102.235 0)
			(effects
				(font
					(size 1.27 1.27)
				)
				(justify left bottom)
				(hide yes)
			)
		)
		(pin "1"
		)
		(pin "2"
		)
		(instances
			(project "sodimm-ddr5-tester"
				(path ""
					(reference "C77")
					(unit 1)
				)
			)
		)
	)
	(symbol
		(lib_id "antmicropower:GND")
		(at 72.39 68.58 0)
		(mirror y)
		(unit 1)
		(exclude_from_sim no)
		(in_bom yes)
		(on_board yes)
		(dnp no)
		(fields_autoplaced yes)
		(property "Reference" "#PWR085"
			(at 72.39 74.93 0)
			(effects
				(font
					(size 1.27 1.27)
				)
				(hide yes)
			)
		)
		(property "Value" "GND"
			(at 74.93 69.85 0)
			(effects
				(font
					(size 1.27 1.27)
					(thickness 0.15)
				)
				(justify right)
			)
		)
		(property "Footprint" ""
			(at 63.5 76.2 0)
			(effects
				(font
					(size 1.27 1.27)
					(thickness 0.15)
				)
				(justify left bottom)
				(hide yes)
			)
		)
		(property "Datasheet" ""
			(at 63.5 81.28 0)
			(effects
				(font
					(size 1.27 1.27)
					(thickness 0.15)
				)
				(justify left bottom)
				(hide yes)
			)
		)
		(property "Description" ""
			(at 63.5 83.82 0)
			(effects
				(font
					(size 1.27 1.27)
				)
				(justify left bottom)
				(hide yes)
			)
		)
		(property "Author" "Antmicro"
			(at 63.5 76.2 0)
			(effects
				(font
					(size 1.27 1.27)
					(thickness 0.15)
				)
				(justify left bottom)
				(hide yes)
			)
		)
		(property "License" "Apache-2.0"
			(at 63.5 78.74 0)
			(effects
				(font
					(size 1.27 1.27)
					(thickness 0.15)
				)
				(justify left bottom)
				(hide yes)
			)
		)
		(pin "1"
		)
		(instances
			(project "sodimm-ddr5-tester"
				(path ""
					(reference "#PWR085")
					(unit 1)
				)
			)
		)
	)
	(symbol
		(lib_id "antmicroCapacitors0402:C_100n_0402")
		(at 100.33 122.555 90)
		(unit 1)
		(exclude_from_sim no)
		(in_bom yes)
		(on_board yes)
		(dnp no)
		(property "Reference" "C64"
			(at 100.965 118.11 90)
			(effects
				(font
					(size 1.27 1.27)
					(thickness 0.15)
				)
				(justify right)
			)
		)
		(property "Value" "C_100n_0402"
			(at 110.49 102.235 0)
			(effects
				(font
					(size 1.27 1.27)
					(thickness 0.15)
				)
				(justify left bottom)
				(hide yes)
			)
		)
		(property "Footprint" "antmicro-footprints:C_0402_1005Metric"
			(at 113.03 102.235 0)
			(effects
				(font
					(size 1.27 1.27)
					(thickness 0.15)
				)
				(justify left bottom)
				(hide yes)
			)
		)
		(property "Datasheet" "https://www.murata.com/products/productdetail?partno=GRM155R61H104KE14%23"
			(at 115.57 102.235 0)
			(effects
				(font
					(size 1.27 1.27)
					(thickness 0.15)
				)
				(justify left bottom)
				(hide yes)
			)
		)
		(property "Description" ""
			(at 100.33 122.555 0)
			(effects
				(font
					(size 1.27 1.27)
				)
			)
		)
		(property "MPN" "GRM155R61H104KE14D"
			(at 118.11 102.235 0)
			(effects
				(font
					(size 1.27 1.27)
					(thickness 0.15)
				)
				(justify left bottom)
				(hide yes)
			)
		)
		(property "Manufacturer" "Murata"
			(at 120.65 102.235 0)
			(effects
				(font
					(size 1.27 1.27)
					(thickness 0.15)
				)
				(justify left bottom)
				(hide yes)
			)
		)
		(property "License" "Apache-2.0"
			(at 123.19 102.235 0)
			(effects
				(font
					(size 1.27 1.27)
					(thickness 0.15)
				)
				(justify left bottom)
				(hide yes)
			)
		)
		(property "Author" "Antmicro"
			(at 125.73 102.235 0)
			(effects
				(font
					(size 1.27 1.27)
					(thickness 0.15)
				)
				(justify left bottom)
				(hide yes)
			)
		)
		(property "Val" "100n"
			(at 100.965 121.92 90)
			(effects
				(font
					(size 1.27 1.27)
					(thickness 0.15)
				)
				(justify right)
			)
		)
		(property "Voltage" "50V"
			(at 128.27 102.235 0)
			(effects
				(font
					(size 1.27 1.27)
				)
				(justify left bottom)
				(hide yes)
			)
		)
		(property "Dielectric" "X5R"
			(at 130.81 102.235 0)
			(effects
				(font
					(size 1.27 1.27)
				)
				(justify left bottom)
				(hide yes)
			)
		)
		(pin "1"
		)
		(pin "2"
		)
		(instances
			(project "sodimm-ddr5-tester"
				(path ""
					(reference "C64")
					(unit 1)
				)
			)
		)
	)
	(symbol
		(lib_id "antmicroCapacitors0603:C_47u_0603")
		(at 38.735 184.15 270)
		(unit 1)
		(exclude_from_sim no)
		(in_bom yes)
		(on_board yes)
		(dnp no)
		(property "Reference" "C16"
			(at 38.735 184.785 90)
			(effects
				(font
					(size 1.27 1.27)
				)
				(justify left)
			)
		)
		(property "Value" "C_47u_0603"
			(at 28.575 204.47 0)
			(effects
				(font
					(size 1.27 1.27)
					(thickness 0.15)
				)
				(justify left bottom)
				(hide yes)
			)
		)
		(property "Footprint" "antmicro-footprints:C_0603_1608Metric"
			(at 26.035 204.47 0)
			(effects
				(font
					(size 1.27 1.27)
					(thickness 0.15)
				)
				(justify left bottom)
				(hide yes)
			)
		)
		(property "Datasheet" "https://www.murata.com/products/productdetail?partno=GRM188R60J476ME15%23"
			(at 23.495 204.47 0)
			(effects
				(font
					(size 1.27 1.27)
					(thickness 0.15)
				)
				(justify left bottom)
				(hide yes)
			)
		)
		(property "Description" ""
			(at 38.735 184.15 0)
			(effects
				(font
					(size 1.27 1.27)
				)
			)
		)
		(property "Manufacturer" "Murata"
			(at 18.415 204.47 0)
			(effects
				(font
					(size 1.27 1.27)
					(thickness 0.15)
				)
				(justify left bottom)
				(hide yes)
			)
		)
		(property "MPN" "GRM188R60J476ME15D"
			(at 20.955 204.47 0)
			(effects
				(font
					(size 1.27 1.27)
					(thickness 0.15)
				)
				(justify left bottom)
				(hide yes)
			)
		)
		(property "Val" "47u"
			(at 38.735 188.595 90)
			(effects
				(font
					(size 1.27 1.27)
					(thickness 0.15)
				)
				(justify left)
			)
		)
		(property "License" "Apache-2.0"
			(at 15.875 204.47 0)
			(effects
				(font
					(size 1.27 1.27)
					(thickness 0.15)
				)
				(justify left bottom)
				(hide yes)
			)
		)
		(property "Author" "Antmicro"
			(at 13.335 204.47 0)
			(effects
				(font
					(size 1.27 1.27)
					(thickness 0.15)
				)
				(justify left bottom)
				(hide yes)
			)
		)
		(property "Voltage" ""
			(at 10.795 204.47 0)
			(effects
				(font
					(size 1.27 1.27)
				)
				(justify left bottom)
				(hide yes)
			)
		)
		(property "Dielectric" ""
			(at 8.255 204.47 0)
			(effects
				(font
					(size 1.27 1.27)
				)
				(justify left bottom)
				(hide yes)
			)
		)
		(pin "1"
		)
		(pin "2"
		)
		(instances
			(project "sodimm-ddr5-tester"
				(path ""
					(reference "C16")
					(unit 1)
				)
			)
		)
	)
	(symbol
		(lib_id "antmicropower:GND")
		(at 66.675 190.5 0)
		(unit 1)
		(exclude_from_sim no)
		(in_bom yes)
		(on_board yes)
		(dnp no)
		(fields_autoplaced yes)
		(property "Reference" "#PWR087"
			(at 66.675 196.85 0)
			(effects
				(font
					(size 1.27 1.27)
				)
				(hide yes)
			)
		)
		(property "Value" "GND"
			(at 68.58 191.77 0)
			(effects
				(font
					(size 1.27 1.27)
					(thickness 0.15)
				)
				(justify left)
			)
		)
		(property "Footprint" ""
			(at 75.565 198.12 0)
			(effects
				(font
					(size 1.27 1.27)
					(thickness 0.15)
				)
				(justify left bottom)
				(hide yes)
			)
		)
		(property "Datasheet" ""
			(at 75.565 203.2 0)
			(effects
				(font
					(size 1.27 1.27)
					(thickness 0.15)
				)
				(justify left bottom)
				(hide yes)
			)
		)
		(property "Description" ""
			(at 75.565 205.74 0)
			(effects
				(font
					(size 1.27 1.27)
				)
				(justify left bottom)
				(hide yes)
			)
		)
		(property "Author" "Antmicro"
			(at 75.565 198.12 0)
			(effects
				(font
					(size 1.27 1.27)
					(thickness 0.15)
				)
				(justify left bottom)
				(hide yes)
			)
		)
		(property "License" "Apache-2.0"
			(at 75.565 200.66 0)
			(effects
				(font
					(size 1.27 1.27)
					(thickness 0.15)
				)
				(justify left bottom)
				(hide yes)
			)
		)
		(pin "1"
		)
		(instances
			(project "sodimm-ddr5-tester"
				(path ""
					(reference "#PWR087")
					(unit 1)
				)
			)
		)
	)
	(symbol
		(lib_id "antmicropower:GND")
		(at 52.705 190.5 0)
		(unit 1)
		(exclude_from_sim no)
		(in_bom yes)
		(on_board yes)
		(dnp no)
		(fields_autoplaced yes)
		(property "Reference" "#PWR076"
			(at 52.705 196.85 0)
			(effects
				(font
					(size 1.27 1.27)
				)
				(hide yes)
			)
		)
		(property "Value" "GND"
			(at 54.61 191.77 0)
			(effects
				(font
					(size 1.27 1.27)
					(thickness 0.15)
				)
				(justify left)
			)
		)
		(property "Footprint" ""
			(at 61.595 198.12 0)
			(effects
				(font
					(size 1.27 1.27)
					(thickness 0.15)
				)
				(justify left bottom)
				(hide yes)
			)
		)
		(property "Datasheet" ""
			(at 61.595 203.2 0)
			(effects
				(font
					(size 1.27 1.27)
					(thickness 0.15)
				)
				(justify left bottom)
				(hide yes)
			)
		)
		(property "Description" ""
			(at 61.595 205.74 0)
			(effects
				(font
					(size 1.27 1.27)
				)
				(justify left bottom)
				(hide yes)
			)
		)
		(property "Author" "Antmicro"
			(at 61.595 198.12 0)
			(effects
				(font
					(size 1.27 1.27)
					(thickness 0.15)
				)
				(justify left bottom)
				(hide yes)
			)
		)
		(property "License" "Apache-2.0"
			(at 61.595 200.66 0)
			(effects
				(font
					(size 1.27 1.27)
					(thickness 0.15)
				)
				(justify left bottom)
				(hide yes)
			)
		)
		(pin "1"
		)
		(instances
			(project "sodimm-ddr5-tester"
				(path ""
					(reference "#PWR076")
					(unit 1)
				)
			)
		)
	)
	(symbol
		(lib_id "antmicropower:GND")
		(at 80.645 220.98 0)
		(unit 1)
		(exclude_from_sim no)
		(in_bom yes)
		(on_board yes)
		(dnp no)
		(fields_autoplaced yes)
		(property "Reference" "#PWR0100"
			(at 80.645 227.33 0)
			(effects
				(font
					(size 1.27 1.27)
				)
				(hide yes)
			)
		)
		(property "Value" "GND"
			(at 82.55 222.25 0)
			(effects
				(font
					(size 1.27 1.27)
					(thickness 0.15)
				)
				(justify left)
			)
		)
		(property "Footprint" ""
			(at 89.535 228.6 0)
			(effects
				(font
					(size 1.27 1.27)
					(thickness 0.15)
				)
				(justify left bottom)
				(hide yes)
			)
		)
		(property "Datasheet" ""
			(at 89.535 233.68 0)
			(effects
				(font
					(size 1.27 1.27)
					(thickness 0.15)
				)
				(justify left bottom)
				(hide yes)
			)
		)
		(property "Description" ""
			(at 89.535 236.22 0)
			(effects
				(font
					(size 1.27 1.27)
				)
				(justify left bottom)
				(hide yes)
			)
		)
		(property "Author" "Antmicro"
			(at 89.535 228.6 0)
			(effects
				(font
					(size 1.27 1.27)
					(thickness 0.15)
				)
				(justify left bottom)
				(hide yes)
			)
		)
		(property "License" "Apache-2.0"
			(at 89.535 231.14 0)
			(effects
				(font
					(size 1.27 1.27)
					(thickness 0.15)
				)
				(justify left bottom)
				(hide yes)
			)
		)
		(pin "1"
		)
		(instances
			(project "sodimm-ddr5-tester"
				(path ""
					(reference "#PWR0100")
					(unit 1)
				)
			)
		)
	)
	(symbol
		(lib_id "antmicroCapacitors0402:C_100n_0402")
		(at 123.19 189.23 90)
		(unit 1)
		(exclude_from_sim no)
		(in_bom yes)
		(on_board yes)
		(dnp no)
		(property "Reference" "C63"
			(at 127.635 184.785 90)
			(effects
				(font
					(size 1.27 1.27)
					(thickness 0.15)
				)
				(justify left)
			)
		)
		(property "Value" "C_100n_0402"
			(at 133.35 168.91 0)
			(effects
				(font
					(size 1.27 1.27)
					(thickness 0.15)
				)
				(justify left bottom)
				(hide yes)
			)
		)
		(property "Footprint" "antmicro-footprints:C_0402_1005Metric"
			(at 135.89 168.91 0)
			(effects
				(font
					(size 1.27 1.27)
					(thickness 0.15)
				)
				(justify left bottom)
				(hide yes)
			)
		)
		(property "Datasheet" "https://www.murata.com/products/productdetail?partno=GRM155R61H104KE14%23"
			(at 138.43 168.91 0)
			(effects
				(font
					(size 1.27 1.27)
					(thickness 0.15)
				)
				(justify left bottom)
				(hide yes)
			)
		)
		(property "Description" ""
			(at 123.19 189.23 0)
			(effects
				(font
					(size 1.27 1.27)
				)
			)
		)
		(property "MPN" "GRM155R61H104KE14D"
			(at 140.97 168.91 0)
			(effects
				(font
					(size 1.27 1.27)
					(thickness 0.15)
				)
				(justify left bottom)
				(hide yes)
			)
		)
		(property "Manufacturer" "Murata"
			(at 143.51 168.91 0)
			(effects
				(font
					(size 1.27 1.27)
					(thickness 0.15)
				)
				(justify left bottom)
				(hide yes)
			)
		)
		(property "License" "Apache-2.0"
			(at 146.05 168.91 0)
			(effects
				(font
					(size 1.27 1.27)
					(thickness 0.15)
				)
				(justify left bottom)
				(hide yes)
			)
		)
		(property "Author" "Antmicro"
			(at 148.59 168.91 0)
			(effects
				(font
					(size 1.27 1.27)
					(thickness 0.15)
				)
				(justify left bottom)
				(hide yes)
			)
		)
		(property "Val" "100n"
			(at 128.905 188.595 90)
			(effects
				(font
					(size 1.27 1.27)
					(thickness 0.15)
				)
				(justify left)
			)
		)
		(property "Voltage" "50V"
			(at 151.13 168.91 0)
			(effects
				(font
					(size 1.27 1.27)
				)
				(justify left bottom)
				(hide yes)
			)
		)
		(property "Dielectric" "X5R"
			(at 153.67 168.91 0)
			(effects
				(font
					(size 1.27 1.27)
				)
				(justify left bottom)
				(hide yes)
			)
		)
		(pin "1"
		)
		(pin "2"
		)
		(instances
			(project "sodimm-ddr5-tester"
				(path ""
					(reference "C63")
					(unit 1)
				)
			)
		)
	)
	(symbol
		(lib_id "antmicropower:+1V1")
		(at 115.57 211.455 0)
		(unit 1)
		(exclude_from_sim no)
		(in_bom yes)
		(on_board yes)
		(dnp no)
		(property "Reference" "#PWR0134"
			(at 115.57 215.265 0)
			(effects
				(font
					(size 1.27 1.27)
				)
				(hide yes)
			)
		)
		(property "Value" "+1V1"
			(at 115.57 207.899 0)
			(effects
				(font
					(size 1.27 1.27)
				)
			)
		)
		(property "Footprint" ""
			(at 115.57 211.455 0)
			(effects
				(font
					(size 1.27 1.27)
				)
				(hide yes)
			)
		)
		(property "Datasheet" ""
			(at 115.57 211.455 0)
			(effects
				(font
					(size 1.27 1.27)
				)
				(hide yes)
			)
		)
		(property "Description" ""
			(at 115.57 211.455 0)
			(effects
				(font
					(size 1.27 1.27)
				)
			)
		)
		(pin "1"
		)
		(instances
			(project "sodimm-ddr5-tester"
				(path ""
					(reference "#PWR0134")
					(unit 1)
				)
			)
		)
	)
	(symbol
		(lib_id "antmicropower:GND")
		(at 108.585 124.46 0)
		(unit 1)
		(exclude_from_sim no)
		(in_bom yes)
		(on_board yes)
		(dnp no)
		(fields_autoplaced yes)
		(property "Reference" "#PWR0116"
			(at 108.585 130.81 0)
			(effects
				(font
					(size 1.27 1.27)
				)
				(hide yes)
			)
		)
		(property "Value" "GND"
			(at 110.49 125.73 0)
			(effects
				(font
					(size 1.27 1.27)
					(thickness 0.15)
				)
				(justify left)
			)
		)
		(property "Footprint" ""
			(at 117.475 132.08 0)
			(effects
				(font
					(size 1.27 1.27)
					(thickness 0.15)
				)
				(justify left bottom)
				(hide yes)
			)
		)
		(property "Datasheet" ""
			(at 117.475 137.16 0)
			(effects
				(font
					(size 1.27 1.27)
					(thickness 0.15)
				)
				(justify left bottom)
				(hide yes)
			)
		)
		(property "Description" ""
			(at 117.475 139.7 0)
			(effects
				(font
					(size 1.27 1.27)
				)
				(justify left bottom)
				(hide yes)
			)
		)
		(property "Author" "Antmicro"
			(at 117.475 132.08 0)
			(effects
				(font
					(size 1.27 1.27)
					(thickness 0.15)
				)
				(justify left bottom)
				(hide yes)
			)
		)
		(property "License" "Apache-2.0"
			(at 117.475 134.62 0)
			(effects
				(font
					(size 1.27 1.27)
					(thickness 0.15)
				)
				(justify left bottom)
				(hide yes)
			)
		)
		(pin "1"
		)
		(instances
			(project "sodimm-ddr5-tester"
				(path ""
					(reference "#PWR0116")
					(unit 1)
				)
			)
		)
	)
	(symbol
		(lib_id "antmicroCapacitors0402:C_100n_0402")
		(at 137.16 160.655 90)
		(unit 1)
		(exclude_from_sim no)
		(in_bom yes)
		(on_board yes)
		(dnp no)
		(property "Reference" "C31"
			(at 137.795 156.21 90)
			(effects
				(font
					(size 1.27 1.27)
					(thickness 0.15)
				)
				(justify right)
			)
		)
		(property "Value" "C_100n_0402"
			(at 147.32 140.335 0)
			(effects
				(font
					(size 1.27 1.27)
					(thickness 0.15)
				)
				(justify left bottom)
				(hide yes)
			)
		)
		(property "Footprint" "antmicro-footprints:C_0402_1005Metric"
			(at 149.86 140.335 0)
			(effects
				(font
					(size 1.27 1.27)
					(thickness 0.15)
				)
				(justify left bottom)
				(hide yes)
			)
		)
		(property "Datasheet" "https://www.murata.com/products/productdetail?partno=GRM155R61H104KE14%23"
			(at 152.4 140.335 0)
			(effects
				(font
					(size 1.27 1.27)
					(thickness 0.15)
				)
				(justify left bottom)
				(hide yes)
			)
		)
		(property "Description" ""
			(at 137.16 160.655 0)
			(effects
				(font
					(size 1.27 1.27)
				)
			)
		)
		(property "MPN" "GRM155R61H104KE14D"
			(at 154.94 140.335 0)
			(effects
				(font
					(size 1.27 1.27)
					(thickness 0.15)
				)
				(justify left bottom)
				(hide yes)
			)
		)
		(property "Manufacturer" "Murata"
			(at 157.48 140.335 0)
			(effects
				(font
					(size 1.27 1.27)
					(thickness 0.15)
				)
				(justify left bottom)
				(hide yes)
			)
		)
		(property "License" "Apache-2.0"
			(at 160.02 140.335 0)
			(effects
				(font
					(size 1.27 1.27)
					(thickness 0.15)
				)
				(justify left bottom)
				(hide yes)
			)
		)
		(property "Author" "Antmicro"
			(at 162.56 140.335 0)
			(effects
				(font
					(size 1.27 1.27)
					(thickness 0.15)
				)
				(justify left bottom)
				(hide yes)
			)
		)
		(property "Val" "100n"
			(at 137.795 160.02 90)
			(effects
				(font
					(size 1.27 1.27)
					(thickness 0.15)
				)
				(justify right)
			)
		)
		(property "Voltage" "50V"
			(at 165.1 140.335 0)
			(effects
				(font
					(size 1.27 1.27)
				)
				(justify left bottom)
				(hide yes)
			)
		)
		(property "Dielectric" "X5R"
			(at 167.64 140.335 0)
			(effects
				(font
					(size 1.27 1.27)
				)
				(justify left bottom)
				(hide yes)
			)
		)
		(pin "1"
		)
		(pin "2"
		)
		(instances
			(project "sodimm-ddr5-tester"
				(path ""
					(reference "C31")
					(unit 1)
				)
			)
		)
	)
	(symbol
		(lib_id "antmicropower:GND")
		(at 39.37 68.58 0)
		(mirror y)
		(unit 1)
		(exclude_from_sim no)
		(in_bom yes)
		(on_board yes)
		(dnp no)
		(fields_autoplaced yes)
		(property "Reference" "#PWR054"
			(at 39.37 74.93 0)
			(effects
				(font
					(size 1.27 1.27)
				)
				(hide yes)
			)
		)
		(property "Value" "GND"
			(at 41.91 69.85 0)
			(effects
				(font
					(size 1.27 1.27)
					(thickness 0.15)
				)
				(justify right)
			)
		)
		(property "Footprint" ""
			(at 30.48 76.2 0)
			(effects
				(font
					(size 1.27 1.27)
					(thickness 0.15)
				)
				(justify left bottom)
				(hide yes)
			)
		)
		(property "Datasheet" ""
			(at 30.48 81.28 0)
			(effects
				(font
					(size 1.27 1.27)
					(thickness 0.15)
				)
				(justify left bottom)
				(hide yes)
			)
		)
		(property "Description" ""
			(at 30.48 83.82 0)
			(effects
				(font
					(size 1.27 1.27)
				)
				(justify left bottom)
				(hide yes)
			)
		)
		(property "Author" "Antmicro"
			(at 30.48 76.2 0)
			(effects
				(font
					(size 1.27 1.27)
					(thickness 0.15)
				)
				(justify left bottom)
				(hide yes)
			)
		)
		(property "License" "Apache-2.0"
			(at 30.48 78.74 0)
			(effects
				(font
					(size 1.27 1.27)
					(thickness 0.15)
				)
				(justify left bottom)
				(hide yes)
			)
		)
		(pin "1"
		)
		(instances
			(project "sodimm-ddr5-tester"
				(path ""
					(reference "#PWR054")
					(unit 1)
				)
			)
		)
	)
	(symbol
		(lib_id "antmicroCapacitors0402:C_100n_0402")
		(at 114.3 93.345 90)
		(unit 1)
		(exclude_from_sim no)
		(in_bom yes)
		(on_board yes)
		(dnp no)
		(property "Reference" "C70"
			(at 114.935 88.9 90)
			(effects
				(font
					(size 1.27 1.27)
					(thickness 0.15)
				)
				(justify right)
			)
		)
		(property "Value" "C_100n_0402"
			(at 124.46 73.025 0)
			(effects
				(font
					(size 1.27 1.27)
					(thickness 0.15)
				)
				(justify left bottom)
				(hide yes)
			)
		)
		(property "Footprint" "antmicro-footprints:C_0402_1005Metric"
			(at 127 73.025 0)
			(effects
				(font
					(size 1.27 1.27)
					(thickness 0.15)
				)
				(justify left bottom)
				(hide yes)
			)
		)
		(property "Datasheet" "https://www.murata.com/products/productdetail?partno=GRM155R61H104KE14%23"
			(at 129.54 73.025 0)
			(effects
				(font
					(size 1.27 1.27)
					(thickness 0.15)
				)
				(justify left bottom)
				(hide yes)
			)
		)
		(property "Description" ""
			(at 114.3 93.345 0)
			(effects
				(font
					(size 1.27 1.27)
				)
			)
		)
		(property "MPN" "GRM155R61H104KE14D"
			(at 132.08 73.025 0)
			(effects
				(font
					(size 1.27 1.27)
					(thickness 0.15)
				)
				(justify left bottom)
				(hide yes)
			)
		)
		(property "Manufacturer" "Murata"
			(at 134.62 73.025 0)
			(effects
				(font
					(size 1.27 1.27)
					(thickness 0.15)
				)
				(justify left bottom)
				(hide yes)
			)
		)
		(property "License" "Apache-2.0"
			(at 137.16 73.025 0)
			(effects
				(font
					(size 1.27 1.27)
					(thickness 0.15)
				)
				(justify left bottom)
				(hide yes)
			)
		)
		(property "Author" "Antmicro"
			(at 139.7 73.025 0)
			(effects
				(font
					(size 1.27 1.27)
					(thickness 0.15)
				)
				(justify left bottom)
				(hide yes)
			)
		)
		(property "Val" "100n"
			(at 114.935 92.71 90)
			(effects
				(font
					(size 1.27 1.27)
					(thickness 0.15)
				)
				(justify right)
			)
		)
		(property "Voltage" "50V"
			(at 142.24 73.025 0)
			(effects
				(font
					(size 1.27 1.27)
				)
				(justify left bottom)
				(hide yes)
			)
		)
		(property "Dielectric" "X5R"
			(at 144.78 73.025 0)
			(effects
				(font
					(size 1.27 1.27)
				)
				(justify left bottom)
				(hide yes)
			)
		)
		(pin "1"
		)
		(pin "2"
		)
		(instances
			(project "sodimm-ddr5-tester"
				(path ""
					(reference "C70")
					(unit 1)
				)
			)
		)
	)
	(symbol
		(lib_id "antmicropower:+3V3")
		(at 38.1 237.49 0)
		(unit 1)
		(exclude_from_sim no)
		(in_bom yes)
		(on_board yes)
		(dnp no)
		(property "Reference" "#PWR059"
			(at 38.1 241.3 0)
			(effects
				(font
					(size 1.27 1.27)
				)
				(hide yes)
			)
		)
		(property "Value" "+3V3"
			(at 34.925 234.95 0)
			(effects
				(font
					(size 1.27 1.27)
					(thickness 0.15)
				)
				(justify left bottom)
			)
		)
		(property "Footprint" ""
			(at 53.34 245.11 0)
			(effects
				(font
					(size 1.27 1.27)
					(thickness 0.15)
				)
				(justify left bottom)
				(hide yes)
			)
		)
		(property "Datasheet" ""
			(at 53.34 247.65 0)
			(effects
				(font
					(size 1.27 1.27)
					(thickness 0.15)
				)
				(justify left bottom)
				(hide yes)
			)
		)
		(property "Description" ""
			(at 38.1 237.49 0)
			(effects
				(font
					(size 1.27 1.27)
				)
			)
		)
		(property "Author" "Antmicro"
			(at 53.34 240.03 0)
			(effects
				(font
					(size 1.27 1.27)
					(thickness 0.15)
				)
				(justify left bottom)
				(hide yes)
			)
		)
		(property "License" "Apache-2.0"
			(at 53.34 242.57 0)
			(effects
				(font
					(size 1.27 1.27)
					(thickness 0.15)
				)
				(justify left bottom)
				(hide yes)
			)
		)
		(pin "1"
		)
		(instances
			(project "sodimm-ddr5-tester"
				(path ""
					(reference "#PWR059")
					(unit 1)
				)
			)
		)
	)
	(symbol
		(lib_id "antmicroCapacitors0402:C_4u7_0402")
		(at 92.075 117.475 270)
		(unit 1)
		(exclude_from_sim no)
		(in_bom yes)
		(on_board yes)
		(dnp no)
		(property "Reference" "C57"
			(at 92.075 118.11 90)
			(effects
				(font
					(size 1.27 1.27)
				)
				(justify left)
			)
		)
		(property "Value" "C_4u7_0402"
			(at 81.915 137.795 0)
			(effects
				(font
					(size 1.27 1.27)
					(thickness 0.15)
				)
				(justify left bottom)
				(hide yes)
			)
		)
		(property "Footprint" "antmicro-footprints:C_0402_1005Metric"
			(at 79.375 137.795 0)
			(effects
				(font
					(size 1.27 1.27)
					(thickness 0.15)
				)
				(justify left bottom)
				(hide yes)
			)
		)
		(property "Datasheet" "https://www.murata.com/products/productdetail?partno=GRM155R61A475MEAA%23"
			(at 76.835 137.795 0)
			(effects
				(font
					(size 1.27 1.27)
					(thickness 0.15)
				)
				(justify left bottom)
				(hide yes)
			)
		)
		(property "Description" ""
			(at 92.075 117.475 0)
			(effects
				(font
					(size 1.27 1.27)
				)
			)
		)
		(property "Manufacturer" "Murata"
			(at 71.755 137.795 0)
			(effects
				(font
					(size 1.27 1.27)
					(thickness 0.15)
				)
				(justify left bottom)
				(hide yes)
			)
		)
		(property "MPN" "GRM155R61A475MEAAD"
			(at 74.295 137.795 0)
			(effects
				(font
					(size 1.27 1.27)
					(thickness 0.15)
				)
				(justify left bottom)
				(hide yes)
			)
		)
		(property "Val" "4u7"
			(at 92.075 121.92 90)
			(effects
				(font
					(size 1.27 1.27)
					(thickness 0.15)
				)
				(justify left)
			)
		)
		(property "License" "Apache-2.0"
			(at 69.215 137.795 0)
			(effects
				(font
					(size 1.27 1.27)
					(thickness 0.15)
				)
				(justify left bottom)
				(hide yes)
			)
		)
		(property "Author" "Antmicro"
			(at 66.675 137.795 0)
			(effects
				(font
					(size 1.27 1.27)
					(thickness 0.15)
				)
				(justify left bottom)
				(hide yes)
			)
		)
		(property "Voltage" ""
			(at 64.135 137.795 0)
			(effects
				(font
					(size 1.27 1.27)
				)
				(justify left bottom)
				(hide yes)
			)
		)
		(property "Dielectric" ""
			(at 61.595 137.795 0)
			(effects
				(font
					(size 1.27 1.27)
				)
				(justify left bottom)
				(hide yes)
			)
		)
		(pin "1"
		)
		(pin "2"
		)
		(instances
			(project "sodimm-ddr5-tester"
				(path ""
					(reference "C57")
					(unit 1)
				)
			)
		)
	)
	(symbol
		(lib_id "antmicropower:GND")
		(at 38.735 190.5 0)
		(unit 1)
		(exclude_from_sim no)
		(in_bom yes)
		(on_board yes)
		(dnp no)
		(fields_autoplaced yes)
		(property "Reference" "#PWR062"
			(at 38.735 196.85 0)
			(effects
				(font
					(size 1.27 1.27)
				)
				(hide yes)
			)
		)
		(property "Value" "GND"
			(at 40.64 191.77 0)
			(effects
				(font
					(size 1.27 1.27)
					(thickness 0.15)
				)
				(justify left)
			)
		)
		(property "Footprint" ""
			(at 47.625 198.12 0)
			(effects
				(font
					(size 1.27 1.27)
					(thickness 0.15)
				)
				(justify left bottom)
				(hide yes)
			)
		)
		(property "Datasheet" ""
			(at 47.625 203.2 0)
			(effects
				(font
					(size 1.27 1.27)
					(thickness 0.15)
				)
				(justify left bottom)
				(hide yes)
			)
		)
		(property "Description" ""
			(at 47.625 205.74 0)
			(effects
				(font
					(size 1.27 1.27)
				)
				(justify left bottom)
				(hide yes)
			)
		)
		(property "Author" "Antmicro"
			(at 47.625 198.12 0)
			(effects
				(font
					(size 1.27 1.27)
					(thickness 0.15)
				)
				(justify left bottom)
				(hide yes)
			)
		)
		(property "License" "Apache-2.0"
			(at 47.625 200.66 0)
			(effects
				(font
					(size 1.27 1.27)
					(thickness 0.15)
				)
				(justify left bottom)
				(hide yes)
			)
		)
		(pin "1"
		)
		(instances
			(project "sodimm-ddr5-tester"
				(path ""
					(reference "#PWR062")
					(unit 1)
				)
			)
		)
	)
	(symbol
		(lib_id "antmicropower:GND")
		(at 116.84 124.46 0)
		(unit 1)
		(exclude_from_sim no)
		(in_bom yes)
		(on_board yes)
		(dnp no)
		(fields_autoplaced yes)
		(property "Reference" "#PWR0120"
			(at 116.84 130.81 0)
			(effects
				(font
					(size 1.27 1.27)
				)
				(hide yes)
			)
		)
		(property "Value" "GND"
			(at 119.38 125.73 0)
			(effects
				(font
					(size 1.27 1.27)
					(thickness 0.15)
				)
				(justify left)
			)
		)
		(property "Footprint" ""
			(at 125.73 132.08 0)
			(effects
				(font
					(size 1.27 1.27)
					(thickness 0.15)
				)
				(justify left bottom)
				(hide yes)
			)
		)
		(property "Datasheet" ""
			(at 125.73 137.16 0)
			(effects
				(font
					(size 1.27 1.27)
					(thickness 0.15)
				)
				(justify left bottom)
				(hide yes)
			)
		)
		(property "Description" ""
			(at 125.73 139.7 0)
			(effects
				(font
					(size 1.27 1.27)
				)
				(justify left bottom)
				(hide yes)
			)
		)
		(property "Author" "Antmicro"
			(at 125.73 132.08 0)
			(effects
				(font
					(size 1.27 1.27)
					(thickness 0.15)
				)
				(justify left bottom)
				(hide yes)
			)
		)
		(property "License" "Apache-2.0"
			(at 125.73 134.62 0)
			(effects
				(font
					(size 1.27 1.27)
					(thickness 0.15)
				)
				(justify left bottom)
				(hide yes)
			)
		)
		(pin "1"
		)
		(instances
			(project "sodimm-ddr5-tester"
				(path ""
					(reference "#PWR0120")
					(unit 1)
				)
			)
		)
	)
	(symbol
		(lib_id "antmicropower:GND")
		(at 92.075 124.46 0)
		(mirror y)
		(unit 1)
		(exclude_from_sim no)
		(in_bom yes)
		(on_board yes)
		(dnp no)
		(fields_autoplaced yes)
		(property "Reference" "#PWR0104"
			(at 92.075 130.81 0)
			(effects
				(font
					(size 1.27 1.27)
				)
				(hide yes)
			)
		)
		(property "Value" "GND"
			(at 93.98 125.73 0)
			(effects
				(font
					(size 1.27 1.27)
					(thickness 0.15)
				)
				(justify right)
			)
		)
		(property "Footprint" ""
			(at 83.185 132.08 0)
			(effects
				(font
					(size 1.27 1.27)
					(thickness 0.15)
				)
				(justify left bottom)
				(hide yes)
			)
		)
		(property "Datasheet" ""
			(at 83.185 137.16 0)
			(effects
				(font
					(size 1.27 1.27)
					(thickness 0.15)
				)
				(justify left bottom)
				(hide yes)
			)
		)
		(property "Description" ""
			(at 83.185 139.7 0)
			(effects
				(font
					(size 1.27 1.27)
				)
				(justify left bottom)
				(hide yes)
			)
		)
		(property "Author" "Antmicro"
			(at 83.185 132.08 0)
			(effects
				(font
					(size 1.27 1.27)
					(thickness 0.15)
				)
				(justify left bottom)
				(hide yes)
			)
		)
		(property "License" "Apache-2.0"
			(at 83.185 134.62 0)
			(effects
				(font
					(size 1.27 1.27)
					(thickness 0.15)
				)
				(justify left bottom)
				(hide yes)
			)
		)
		(pin "1"
		)
		(instances
			(project "sodimm-ddr5-tester"
				(path ""
					(reference "#PWR0104")
					(unit 1)
				)
			)
		)
	)
	(symbol
		(lib_id "antmicropower:GND")
		(at 122.555 222.25 0)
		(unit 1)
		(exclude_from_sim no)
		(in_bom yes)
		(on_board yes)
		(dnp no)
		(fields_autoplaced yes)
		(property "Reference" "#PWR0137"
			(at 122.555 228.6 0)
			(effects
				(font
					(size 1.27 1.27)
				)
				(hide yes)
			)
		)
		(property "Value" "GND"
			(at 124.46 223.52 0)
			(effects
				(font
					(size 1.27 1.27)
					(thickness 0.15)
				)
				(justify left)
			)
		)
		(property "Footprint" ""
			(at 131.445 229.87 0)
			(effects
				(font
					(size 1.27 1.27)
					(thickness 0.15)
				)
				(justify left bottom)
				(hide yes)
			)
		)
		(property "Datasheet" ""
			(at 131.445 234.95 0)
			(effects
				(font
					(size 1.27 1.27)
					(thickness 0.15)
				)
				(justify left bottom)
				(hide yes)
			)
		)
		(property "Description" ""
			(at 131.445 237.49 0)
			(effects
				(font
					(size 1.27 1.27)
				)
				(justify left bottom)
				(hide yes)
			)
		)
		(property "Author" "Antmicro"
			(at 131.445 229.87 0)
			(effects
				(font
					(size 1.27 1.27)
					(thickness 0.15)
				)
				(justify left bottom)
				(hide yes)
			)
		)
		(property "License" "Apache-2.0"
			(at 131.445 232.41 0)
			(effects
				(font
					(size 1.27 1.27)
					(thickness 0.15)
				)
				(justify left bottom)
				(hide yes)
			)
		)
		(pin "1"
		)
		(instances
			(project "sodimm-ddr5-tester"
				(path ""
					(reference "#PWR0137")
					(unit 1)
				)
			)
		)
	)
	(symbol
		(lib_id "antmicropower:GND")
		(at 155.575 94.615 0)
		(unit 1)
		(exclude_from_sim no)
		(in_bom yes)
		(on_board yes)
		(dnp no)
		(fields_autoplaced yes)
		(property "Reference" "#PWR0138"
			(at 155.575 100.965 0)
			(effects
				(font
					(size 1.27 1.27)
				)
				(hide yes)
			)
		)
		(property "Value" "GND"
			(at 157.48 95.885 0)
			(effects
				(font
					(size 1.27 1.27)
					(thickness 0.15)
				)
				(justify left)
			)
		)
		(property "Footprint" ""
			(at 164.465 102.235 0)
			(effects
				(font
					(size 1.27 1.27)
					(thickness 0.15)
				)
				(justify left bottom)
				(hide yes)
			)
		)
		(property "Datasheet" ""
			(at 164.465 107.315 0)
			(effects
				(font
					(size 1.27 1.27)
					(thickness 0.15)
				)
				(justify left bottom)
				(hide yes)
			)
		)
		(property "Description" ""
			(at 164.465 109.855 0)
			(effects
				(font
					(size 1.27 1.27)
				)
				(justify left bottom)
				(hide yes)
			)
		)
		(property "Author" "Antmicro"
			(at 164.465 102.235 0)
			(effects
				(font
					(size 1.27 1.27)
					(thickness 0.15)
				)
				(justify left bottom)
				(hide yes)
			)
		)
		(property "License" "Apache-2.0"
			(at 164.465 104.775 0)
			(effects
				(font
					(size 1.27 1.27)
					(thickness 0.15)
				)
				(justify left bottom)
				(hide yes)
			)
		)
		(pin "1"
		)
		(instances
			(project "sodimm-ddr5-tester"
				(path ""
					(reference "#PWR0138")
					(unit 1)
				)
			)
		)
	)
	(symbol
		(lib_id "antmicroCapacitors0402:C_100n_0402")
		(at 108.585 122.555 90)
		(unit 1)
		(exclude_from_sim no)
		(in_bom yes)
		(on_board yes)
		(dnp no)
		(property "Reference" "C68"
			(at 109.22 118.11 90)
			(effects
				(font
					(size 1.27 1.27)
					(thickness 0.15)
				)
				(justify right)
			)
		)
		(property "Value" "C_100n_0402"
			(at 118.745 102.235 0)
			(effects
				(font
					(size 1.27 1.27)
					(thickness 0.15)
				)
				(justify left bottom)
				(hide yes)
			)
		)
		(property "Footprint" "antmicro-footprints:C_0402_1005Metric"
			(at 121.285 102.235 0)
			(effects
				(font
					(size 1.27 1.27)
					(thickness 0.15)
				)
				(justify left bottom)
				(hide yes)
			)
		)
		(property "Datasheet" "https://www.murata.com/products/productdetail?partno=GRM155R61H104KE14%23"
			(at 123.825 102.235 0)
			(effects
				(font
					(size 1.27 1.27)
					(thickness 0.15)
				)
				(justify left bottom)
				(hide yes)
			)
		)
		(property "Description" ""
			(at 108.585 122.555 0)
			(effects
				(font
					(size 1.27 1.27)
				)
			)
		)
		(property "MPN" "GRM155R61H104KE14D"
			(at 126.365 102.235 0)
			(effects
				(font
					(size 1.27 1.27)
					(thickness 0.15)
				)
				(justify left bottom)
				(hide yes)
			)
		)
		(property "Manufacturer" "Murata"
			(at 128.905 102.235 0)
			(effects
				(font
					(size 1.27 1.27)
					(thickness 0.15)
				)
				(justify left bottom)
				(hide yes)
			)
		)
		(property "License" "Apache-2.0"
			(at 131.445 102.235 0)
			(effects
				(font
					(size 1.27 1.27)
					(thickness 0.15)
				)
				(justify left bottom)
				(hide yes)
			)
		)
		(property "Author" "Antmicro"
			(at 133.985 102.235 0)
			(effects
				(font
					(size 1.27 1.27)
					(thickness 0.15)
				)
				(justify left bottom)
				(hide yes)
			)
		)
		(property "Val" "100n"
			(at 109.22 121.92 90)
			(effects
				(font
					(size 1.27 1.27)
					(thickness 0.15)
				)
				(justify right)
			)
		)
		(property "Voltage" "50V"
			(at 136.525 102.235 0)
			(effects
				(font
					(size 1.27 1.27)
				)
				(justify left bottom)
				(hide yes)
			)
		)
		(property "Dielectric" "X5R"
			(at 139.065 102.235 0)
			(effects
				(font
					(size 1.27 1.27)
				)
				(justify left bottom)
				(hide yes)
			)
		)
		(pin "1"
		)
		(pin "2"
		)
		(instances
			(project "sodimm-ddr5-tester"
				(path ""
					(reference "C68")
					(unit 1)
				)
			)
		)
	)
	(symbol
		(lib_id "antmicroCapacitorspol:C_Pol_330u_6.3V_KEMET-T520-B")
		(at 72.39 62.23 270)
		(unit 1)
		(exclude_from_sim no)
		(in_bom yes)
		(on_board yes)
		(dnp no)
		(property "Reference" "C38"
			(at 74.803 63.406 90)
			(effects
				(font
					(size 1.27 1.27)
					(thickness 0.15)
				)
				(justify left)
			)
		)
		(property "Value" "C_Pol_330u_6.3V_KEMET-T520-B"
			(at 69.85 76.2 0)
			(effects
				(font
					(size 1.27 1.27)
					(thickness 0.15)
				)
				(justify left bottom)
				(hide yes)
			)
		)
		(property "Footprint" "antmicro-footprints:C_Pol_EIA-B"
			(at 64.77 76.2 0)
			(effects
				(font
					(size 1.27 1.27)
					(thickness 0.15)
				)
				(justify left bottom)
				(hide yes)
			)
		)
		(property "Datasheet" "https://content.kemet.com/datasheets/KEM_T2076_T52X-530.pdf"
			(at 62.23 76.2 0)
			(effects
				(font
					(size 1.27 1.27)
					(thickness 0.15)
				)
				(justify left bottom)
				(hide yes)
			)
		)
		(property "Description" ""
			(at 72.39 62.23 0)
			(effects
				(font
					(size 1.27 1.27)
				)
			)
		)
		(property "Val" "330u/6.3V"
			(at 74.93 66.04 90)
			(effects
				(font
					(size 1.27 1.27)
					(thickness 0.15)
				)
				(justify left)
			)
		)
		(property "MPN" "T520B337M006ATE040"
			(at 59.69 76.2 0)
			(effects
				(font
					(size 1.27 1.27)
					(thickness 0.15)
				)
				(justify left bottom)
				(hide yes)
			)
		)
		(property "Manufacturer" "KEMET"
			(at 57.15 76.2 0)
			(effects
				(font
					(size 1.27 1.27)
					(thickness 0.15)
				)
				(justify left bottom)
				(hide yes)
			)
		)
		(property "License" "Apache-2.0"
			(at 54.61 76.2 0)
			(effects
				(font
					(size 1.27 1.27)
					(thickness 0.15)
				)
				(justify left bottom)
				(hide yes)
			)
		)
		(property "Author" "Antmicro"
			(at 52.07 76.2 0)
			(effects
				(font
					(size 1.27 1.27)
					(thickness 0.15)
				)
				(justify left bottom)
				(hide yes)
			)
		)
		(property "Voltage" "6.3V"
			(at 49.53 76.2 0)
			(effects
				(font
					(size 1.27 1.27)
				)
				(justify left bottom)
				(hide yes)
			)
		)
		(pin "1"
		)
		(pin "2"
		)
		(instances
			(project "sodimm-ddr5-tester"
				(path ""
					(reference "C38")
					(unit 1)
				)
			)
		)
	)
	(symbol
		(lib_id "antmicropower:GND")
		(at 81.28 94.615 0)
		(unit 1)
		(exclude_from_sim no)
		(in_bom yes)
		(on_board yes)
		(dnp no)
		(fields_autoplaced yes)
		(property "Reference" "#PWR095"
			(at 81.28 100.965 0)
			(effects
				(font
					(size 1.27 1.27)
				)
				(hide yes)
			)
		)
		(property "Value" "GND"
			(at 83.82 95.885 0)
			(effects
				(font
					(size 1.27 1.27)
					(thickness 0.15)
				)
				(justify left)
			)
		)
		(property "Footprint" ""
			(at 90.17 102.235 0)
			(effects
				(font
					(size 1.27 1.27)
					(thickness 0.15)
				)
				(justify left bottom)
				(hide yes)
			)
		)
		(property "Datasheet" ""
			(at 90.17 107.315 0)
			(effects
				(font
					(size 1.27 1.27)
					(thickness 0.15)
				)
				(justify left bottom)
				(hide yes)
			)
		)
		(property "Description" ""
			(at 90.17 109.855 0)
			(effects
				(font
					(size 1.27 1.27)
				)
				(justify left bottom)
				(hide yes)
			)
		)
		(property "Author" "Antmicro"
			(at 90.17 102.235 0)
			(effects
				(font
					(size 1.27 1.27)
					(thickness 0.15)
				)
				(justify left bottom)
				(hide yes)
			)
		)
		(property "License" "Apache-2.0"
			(at 90.17 104.775 0)
			(effects
				(font
					(size 1.27 1.27)
					(thickness 0.15)
				)
				(justify left bottom)
				(hide yes)
			)
		)
		(pin "1"
		)
		(instances
			(project "sodimm-ddr5-tester"
				(path ""
					(reference "#PWR095")
					(unit 1)
				)
			)
		)
	)
	(symbol
		(lib_id "antmicroCapacitors0402:C_100n_0402")
		(at 59.69 219.71 90)
		(unit 1)
		(exclude_from_sim no)
		(in_bom yes)
		(on_board yes)
		(dnp no)
		(property "Reference" "C36"
			(at 60.325 215.265 90)
			(effects
				(font
					(size 1.27 1.27)
					(thickness 0.15)
				)
				(justify right)
			)
		)
		(property "Value" "C_100n_0402"
			(at 69.85 199.39 0)
			(effects
				(font
					(size 1.27 1.27)
					(thickness 0.15)
				)
				(justify left bottom)
				(hide yes)
			)
		)
		(property "Footprint" "antmicro-footprints:C_0402_1005Metric"
			(at 72.39 199.39 0)
			(effects
				(font
					(size 1.27 1.27)
					(thickness 0.15)
				)
				(justify left bottom)
				(hide yes)
			)
		)
		(property "Datasheet" "https://www.murata.com/products/productdetail?partno=GRM155R61H104KE14%23"
			(at 74.93 199.39 0)
			(effects
				(font
					(size 1.27 1.27)
					(thickness 0.15)
				)
				(justify left bottom)
				(hide yes)
			)
		)
		(property "Description" ""
			(at 59.69 219.71 0)
			(effects
				(font
					(size 1.27 1.27)
				)
			)
		)
		(property "MPN" "GRM155R61H104KE14D"
			(at 77.47 199.39 0)
			(effects
				(font
					(size 1.27 1.27)
					(thickness 0.15)
				)
				(justify left bottom)
				(hide yes)
			)
		)
		(property "Manufacturer" "Murata"
			(at 80.01 199.39 0)
			(effects
				(font
					(size 1.27 1.27)
					(thickness 0.15)
				)
				(justify left bottom)
				(hide yes)
			)
		)
		(property "License" "Apache-2.0"
			(at 82.55 199.39 0)
			(effects
				(font
					(size 1.27 1.27)
					(thickness 0.15)
				)
				(justify left bottom)
				(hide yes)
			)
		)
		(property "Author" "Antmicro"
			(at 85.09 199.39 0)
			(effects
				(font
					(size 1.27 1.27)
					(thickness 0.15)
				)
				(justify left bottom)
				(hide yes)
			)
		)
		(property "Val" "100n"
			(at 60.325 219.075 90)
			(effects
				(font
					(size 1.27 1.27)
					(thickness 0.15)
				)
				(justify right)
			)
		)
		(property "Voltage" "50V"
			(at 87.63 199.39 0)
			(effects
				(font
					(size 1.27 1.27)
				)
				(justify left bottom)
				(hide yes)
			)
		)
		(property "Dielectric" "X5R"
			(at 90.17 199.39 0)
			(effects
				(font
					(size 1.27 1.27)
				)
				(justify left bottom)
				(hide yes)
			)
		)
		(pin "1"
		)
		(pin "2"
		)
		(instances
			(project "sodimm-ddr5-tester"
				(path ""
					(reference "C36")
					(unit 1)
				)
			)
		)
	)
	(symbol
		(lib_id "antmicropower:GND")
		(at 87.63 190.5 0)
		(unit 1)
		(exclude_from_sim no)
		(in_bom yes)
		(on_board yes)
		(dnp no)
		(fields_autoplaced yes)
		(property "Reference" "#PWR0105"
			(at 87.63 196.85 0)
			(effects
				(font
					(size 1.27 1.27)
				)
				(hide yes)
			)
		)
		(property "Value" "GND"
			(at 90.17 191.77 0)
			(effects
				(font
					(size 1.27 1.27)
					(thickness 0.15)
				)
				(justify left)
			)
		)
		(property "Footprint" ""
			(at 96.52 198.12 0)
			(effects
				(font
					(size 1.27 1.27)
					(thickness 0.15)
				)
				(justify left bottom)
				(hide yes)
			)
		)
		(property "Datasheet" ""
			(at 96.52 203.2 0)
			(effects
				(font
					(size 1.27 1.27)
					(thickness 0.15)
				)
				(justify left bottom)
				(hide yes)
			)
		)
		(property "Description" ""
			(at 96.52 205.74 0)
			(effects
				(font
					(size 1.27 1.27)
				)
				(justify left bottom)
				(hide yes)
			)
		)
		(property "Author" "Antmicro"
			(at 96.52 198.12 0)
			(effects
				(font
					(size 1.27 1.27)
					(thickness 0.15)
				)
				(justify left bottom)
				(hide yes)
			)
		)
		(property "License" "Apache-2.0"
			(at 96.52 200.66 0)
			(effects
				(font
					(size 1.27 1.27)
					(thickness 0.15)
				)
				(justify left bottom)
				(hide yes)
			)
		)
		(pin "1"
		)
		(instances
			(project "sodimm-ddr5-tester"
				(path ""
					(reference "#PWR0105")
					(unit 1)
				)
			)
		)
	)
	(symbol
		(lib_id "antmicropower:GND")
		(at 45.72 161.925 0)
		(unit 1)
		(exclude_from_sim no)
		(in_bom yes)
		(on_board yes)
		(dnp no)
		(fields_autoplaced yes)
		(property "Reference" "#PWR0125"
			(at 45.72 168.275 0)
			(effects
				(font
					(size 1.27 1.27)
				)
				(hide yes)
			)
		)
		(property "Value" "GND"
			(at 48.26 163.195 0)
			(effects
				(font
					(size 1.27 1.27)
					(thickness 0.15)
				)
				(justify left)
			)
		)
		(property "Footprint" ""
			(at 54.61 169.545 0)
			(effects
				(font
					(size 1.27 1.27)
					(thickness 0.15)
				)
				(justify left bottom)
				(hide yes)
			)
		)
		(property "Datasheet" ""
			(at 54.61 174.625 0)
			(effects
				(font
					(size 1.27 1.27)
					(thickness 0.15)
				)
				(justify left bottom)
				(hide yes)
			)
		)
		(property "Description" ""
			(at 54.61 177.165 0)
			(effects
				(font
					(size 1.27 1.27)
				)
				(justify left bottom)
				(hide yes)
			)
		)
		(property "Author" "Antmicro"
			(at 54.61 169.545 0)
			(effects
				(font
					(size 1.27 1.27)
					(thickness 0.15)
				)
				(justify left bottom)
				(hide yes)
			)
		)
		(property "License" "Apache-2.0"
			(at 54.61 172.085 0)
			(effects
				(font
					(size 1.27 1.27)
					(thickness 0.15)
				)
				(justify left bottom)
				(hide yes)
			)
		)
		(pin "1"
		)
		(instances
			(project "sodimm-ddr5-tester"
				(path ""
					(reference "#PWR0125")
					(unit 1)
				)
			)
		)
	)
	(symbol
		(lib_id "antmicropower:GND")
		(at 52.705 220.98 0)
		(unit 1)
		(exclude_from_sim no)
		(in_bom yes)
		(on_board yes)
		(dnp no)
		(fields_autoplaced yes)
		(property "Reference" "#PWR077"
			(at 52.705 227.33 0)
			(effects
				(font
					(size 1.27 1.27)
				)
				(hide yes)
			)
		)
		(property "Value" "GND"
			(at 54.61 222.25 0)
			(effects
				(font
					(size 1.27 1.27)
					(thickness 0.15)
				)
				(justify left)
			)
		)
		(property "Footprint" ""
			(at 61.595 228.6 0)
			(effects
				(font
					(size 1.27 1.27)
					(thickness 0.15)
				)
				(justify left bottom)
				(hide yes)
			)
		)
		(property "Datasheet" ""
			(at 61.595 233.68 0)
			(effects
				(font
					(size 1.27 1.27)
					(thickness 0.15)
				)
				(justify left bottom)
				(hide yes)
			)
		)
		(property "Description" ""
			(at 61.595 236.22 0)
			(effects
				(font
					(size 1.27 1.27)
				)
				(justify left bottom)
				(hide yes)
			)
		)
		(property "Author" "Antmicro"
			(at 61.595 228.6 0)
			(effects
				(font
					(size 1.27 1.27)
					(thickness 0.15)
				)
				(justify left bottom)
				(hide yes)
			)
		)
		(property "License" "Apache-2.0"
			(at 61.595 231.14 0)
			(effects
				(font
					(size 1.27 1.27)
					(thickness 0.15)
				)
				(justify left bottom)
				(hide yes)
			)
		)
		(pin "1"
		)
		(instances
			(project "sodimm-ddr5-tester"
				(path ""
					(reference "#PWR077")
					(unit 1)
				)
			)
		)
	)
	(symbol
		(lib_id "antmicroCapacitors0402:C_100n_0402")
		(at 86.995 247.65 90)
		(unit 1)
		(exclude_from_sim no)
		(in_bom yes)
		(on_board yes)
		(dnp no)
		(property "Reference" "C56"
			(at 87.63 243.205 90)
			(effects
				(font
					(size 1.27 1.27)
					(thickness 0.15)
				)
				(justify right)
			)
		)
		(property "Value" "C_100n_0402"
			(at 97.155 227.33 0)
			(effects
				(font
					(size 1.27 1.27)
					(thickness 0.15)
				)
				(justify left bottom)
				(hide yes)
			)
		)
		(property "Footprint" "antmicro-footprints:C_0402_1005Metric"
			(at 99.695 227.33 0)
			(effects
				(font
					(size 1.27 1.27)
					(thickness 0.15)
				)
				(justify left bottom)
				(hide yes)
			)
		)
		(property "Datasheet" "https://www.murata.com/products/productdetail?partno=GRM155R61H104KE14%23"
			(at 102.235 227.33 0)
			(effects
				(font
					(size 1.27 1.27)
					(thickness 0.15)
				)
				(justify left bottom)
				(hide yes)
			)
		)
		(property "Description" ""
			(at 86.995 247.65 0)
			(effects
				(font
					(size 1.27 1.27)
				)
			)
		)
		(property "MPN" "GRM155R61H104KE14D"
			(at 104.775 227.33 0)
			(effects
				(font
					(size 1.27 1.27)
					(thickness 0.15)
				)
				(justify left bottom)
				(hide yes)
			)
		)
		(property "Manufacturer" "Murata"
			(at 107.315 227.33 0)
			(effects
				(font
					(size 1.27 1.27)
					(thickness 0.15)
				)
				(justify left bottom)
				(hide yes)
			)
		)
		(property "License" "Apache-2.0"
			(at 109.855 227.33 0)
			(effects
				(font
					(size 1.27 1.27)
					(thickness 0.15)
				)
				(justify left bottom)
				(hide yes)
			)
		)
		(property "Author" "Antmicro"
			(at 112.395 227.33 0)
			(effects
				(font
					(size 1.27 1.27)
					(thickness 0.15)
				)
				(justify left bottom)
				(hide yes)
			)
		)
		(property "Val" "100n"
			(at 87.63 247.015 90)
			(effects
				(font
					(size 1.27 1.27)
					(thickness 0.15)
				)
				(justify right)
			)
		)
		(property "Voltage" "50V"
			(at 114.935 227.33 0)
			(effects
				(font
					(size 1.27 1.27)
				)
				(justify left bottom)
				(hide yes)
			)
		)
		(property "Dielectric" "X5R"
			(at 117.475 227.33 0)
			(effects
				(font
					(size 1.27 1.27)
				)
				(justify left bottom)
				(hide yes)
			)
		)
		(pin "1"
		)
		(pin "2"
		)
		(instances
			(project "sodimm-ddr5-tester"
				(path ""
					(reference "C56")
					(unit 1)
				)
			)
		)
	)
)
